# Lightning_PEB_EQL.xlsx — LeopardBWlength (si-constraints)
| 5007-1a/15007-1a.brd |  |  |  |
| Date Wed Nov 18 15:01:03 2015 |  |  |  |
| Net Name | Etch Length (mils) | Manhattan Length (mils) | Percent Manhattan (mils) |
| ADCAV33 | 22.27 | 261.45 | 8.52 |
| ADCVREFFN | 88.81 | 71.28 | 124.59 |
| ADCVREFFP | 82.01 | 188.19 | 43.58 |
| ADCVREXT | 52.95 | 50.54 | 104.77 |
| ADC_12V_PCIE | 2562.5300000000002 | 2212.09 | 115.84 |
| ADC_P1V05_STBY_PCH | 1851.36 | 1224 | 151.26 |
| ADC_P1V8_STBY | 1818.93 | 1416.8 | 128.38 |
| ADC_P3V3 | 2616.5500000000002 | 2329.35 | 112.33 |
| ADC_P3V3_STBY | 847.27 | 774.77 | 109.36 |
| ADC_P3V3_VBAT | 2118.44 | 2058.7800000000002 | 102.9 |
| ADC_P3V3_VBAT_G | 327.78 | 282.07 | 116.21 |
| ADC_P3V3_VBAT_Q | 169.41 | 186 | 91.08 |
| ADC_P5V | 2262.23 | 2300.2800000000002 | 98.35 |
| ADC_P5V_STBY | 1669.62 | 1264.03 | 132.09 |
| AGND_CURRENT_MON | 1529.68 | 4181.5200000000004 | 36.58 |
| AGND_P1V05_PCH | 0 | 283 | 0 |
| AGND_P1V05_STBY_PCH | 222.44 | 328.65 | 67.680000000000007 |
| AGND_P1V8_STBY_BMC | 282.29000000000002 | 376.13 | 75.05 |
| AGND_P3V3 | 38.909999999999997 | 325.94 | 11.94 |
| AGND_P3V3_STBY | 237.94 | 252 | 94.42 |
| AGND_P5V | 0 | 192.85 | 0 |
| AGND_PVCCIO | 414.43 | 453.75 | 91.33 |
| AGND_PVPP_AB | 523.55999999999995 | 368.22 | 142.19 |
| AGND_PVPP_CD | 285.2 | 305.60000000000002 | 93.33 |
| AGND_PVPP_EF | 426.38 | 319.20999999999998 | 133.57 |
| AGND_PVPP_GH | 448.27 | 418.54 | 107.1 |
| ARM_NTRST | 222.17 | 224.87 | 98.8 |
| ARM_RTCK | 483.68 | 456.98 | 105.84 |
| ARM_TCK | 5187.4799999999996 | 4053.49 | 127.98 |
| ARM_TDI | 5829.55 | 4679.96 | 124.56 |
| ARM_TDO | 4895.75 | 4562.26 | 107.31 |
| ARM_TMS | 4233.88 | 3911.22 | 108.25 |
| AS_EXTRST_N | 676.11 | 480.6 | 140.68 |
| AS_ROMA0_R | 263.94 | 237.34 | 111.21 |
| AUD_AZA_SDO | 5993.68 | 4138.13 | 144.84 |
| AUD_AZA_SDO_R | 224.82 | 191.65 | 117.31 |
| BEEP_LED | 519.95000000000005 | 648.76 | 80.150000000000006 |
| BIOS_ERR_TRIGGER_N | 12450.73 | 11933.34 | 104.34 |
| BIOS_FW_GD_N | 6708.6 | 6070.55 | 110.51 |
| BIOS_SPI_MUX_S | 3845.85 | 3503.94 | 109.76 |
| BIOS_SPI_OE_N | 369.18 | 397 | 92.99 |
| BMC_CURRENT_EN | 6045.08 | 5423.58 | 111.46 |
| BMC_CURRENT_EN_CPLD | 293.95999999999998 | 205.94 | 142.74 |
| BMC_DDR3_GATE | 201.14 | 118.67 | 169.5 |
| BMC_DDR3_RST_N | 307.05 | 236.2 | 130 |
| BMC_HIGH_HEX_0 | 6258.32 | 6127.98 | 102.13 |
| BMC_HIGH_HEX_1 | 5968.62 | 6092.47 | 97.97 |
| BMC_HIGH_HEX_2 | 6114.37 | 6293.97 | 97.15 |
| BMC_HIGH_HEX_3 | 6307.13 | 6183.98 | 101.99 |
| BMC_JTAG_SELECT | 4593.88 | 4354.37 | 105.5 |
| BMC_LED_ACTIVE | 4071.77 | 3249.19 | 125.32 |
| BMC_LED_CATERR | 3117.32 | 3044.94 | 102.38 |
| BMC_LED_N | 2659.75 | 2840.65 | 93.63 |
| BMC_LED_R_N | 100.3 | 76.97 | 130.30000000000001 |
| BMC_LOW_HEX_0 | 6003.39 | 5517.98 | 108.8 |
| BMC_LOW_HEX_1 | 5774.72 | 5644.48 | 102.31 |
| BMC_LOW_HEX_2 | 6001.66 | 6005.97 | 99.93 |
| BMC_LOW_HEX_3 | 6384.43 | 5448.47 | 117.18 |
| BMC_PCIE_PERST_N | 717.05 | 824.38 | 86.98 |
| BMC_PCIE_WAKE_N | 731.96 | 660.06 | 110.89 |
| BMC_PEREXT | 222.03 | 276.72000000000003 | 80.23 |
| BMC_PWRBTN_N | 5568.17 | 5194.09 | 107.2 |
| BMC_READY_C | 965.33 | 1104.75 | 87.38 |
| BMC_READY_R | 385.65 | 418.85 | 92.07 |
| BMC_RESET_N | 12137.21 | 6723.41 | 180.52 |
| BMC_RESET_R_N | 159.47 | 198.06 | 80.52 |
| BMC_SPI_CS | 6178.87 | 2924.5 | 211.28 |
| BMC_TCK | 207.36 | 244.38 | 84.85 |
| BMC_TDI | 130.05000000000001 | 140.59 | 92.5 |
| BMC_TDO | 172.55 | 199.38 | 86.54 |
| BMC_TMS | 518.55999999999995 | 461.99 | 112.24 |
| BMC_UART_L_LED | 291.27999999999997 | 323.05 | 90.17 |
| BMC_UART_R_LED | 652.11 | 589.98 | 110.53 |
| BOARD_ID0 | 279.67 | 298.77 | 93.61 |
| BOARD_ID1 | 303.07 | 365.65 | 82.89 |
| BOARD_ID2 | 403.72 | 407.51 | 99.07 |
| BOARD_ID3 | 315.48 | 388.3 | 81.25 |
| BOARD_ID0_PCH | 267.10000000000002 | 220.64 | 121.06 |
| BOARD_ID1_PCH | 690.09 | 826.18 | 83.53 |
| BOARD_ID2_PCH | 181.97 | 181.8 | 100.09 |
| BOARD_ID3_PCH | 1004.15 | 1047.3399999999999 | 95.88 |
| BTN_FUNC_EN_N | 6599.97 | 5385.36 | 122.55 |
| CATERR_LED_N | 3841.08 | 2543.13 | 151.04 |
| CATERR_LED_R_N | 137.68 | 172.5 | 79.81 |
| CH_SELECT0 | 11643.62 | 6111.78 | 190.51 |
| CH_SELECT1 | 13144.9 | 6464.96 | 203.33 |
| CH_SELECT0_BMC | 1272.31 | 1194.77 | 106.49 |
| CH_SELECT1_BMC | 1190.3499999999999 | 1049.58 | 113.41 |
| CLK_100M_CPU0_BCLK0_DN | 17037.810000000001 | 8974.6 | 189.84 |
| CLK_100M_CPU0_BCLK0_DP | 17040.05 | 8974.77 | 189.87 |
| CLK_100M_CPU0_BCLK0_R_DN | 343.46 | 361.08 | 95.12 |
| CLK_100M_CPU0_BCLK0_R_DP | 343.9 | 421.56 | 81.58 |
| CLK_100M_CPU0_BCLK1_DN | 17057.48 | 8216.64 | 207.6 |
| CLK_100M_CPU0_BCLK1_DP | 17059.439999999999 | 8297.6200000000008 | 205.59 |
| CLK_100M_CPU0_BCLK1_R_DN | 241.56 | 221.5 | 109.05 |
| CLK_100M_CPU0_BCLK1_R_DP | 242.56 | 283.05 | 85.7 |
| CLK_100M_CPU1_BCLK0_DN | 17008.32 | 12208.66 | 139.31 |
| CLK_100M_CPU1_BCLK0_DP | 17010.900000000001 | 12288.66 | 138.43 |
| CLK_100M_CPU1_BCLK0_R_DN | 91.96 | 93.09 | 98.78 |
| CLK_100M_CPU1_BCLK0_R_DP | 91.33 | 114.39 | 79.84 |
| CLK_100M_CPU1_BCLK1_DN | 17021.28 | 12632.56 | 134.74 |
| CLK_100M_CPU1_BCLK1_DP | 17026.740000000002 | 12633.52 | 134.77000000000001 |
| CLK_100M_CPU1_BCLK1_R_DN | 143.34 | 165.85 | 86.43 |
| CLK_100M_CPU1_BCLK1_R_DP | 144.41999999999999 | 143.55000000000001 | 100.61 |
| CLK_100M_DB1900Z_FB_DN | 311.10000000000002 | 258.35000000000002 | 120.42 |
| CLK_100M_DB1900Z_FB_DP | 313.60000000000002 | 279.44 | 112.23 |
| CLK_100M_DB1900Z_FB_R_DN | 283.06 | 244.07 | 115.98 |
| CLK_100M_DB1900Z_FB_R_DP | 284.39 | 303.49 | 93.71 |
| CLK_100M_DB1900_DN | 519.03 | 524.61 | 98.94 |
| CLK_100M_DB1900_DP | 518.59 | 463.91 | 111.79 |
| CLK_100M_DB1900_PCH_CPY_R_DN | 177.86 | 209.6 | 84.86 |
| CLK_100M_DB1900_PCH_CPY_R_DP | 177.86 | 188.25 | 94.48 |
| CLK_100M_MEZZ1_DN | 8324.9500000000007 | 5913.99 | 140.77000000000001 |
| CLK_100M_MEZZ1_DP | 8322.2999999999993 | 5984.16 | 139.07 |
| CLK_100M_MEZZ1_R_DN | 142.88 | 144.79 | 98.68 |
| CLK_100M_MEZZ1_R_DP | 141.88999999999999 | 144.21 | 98.39 |
| CLK_100M_MEZZ2_DN | 8332.67 | 5716.17 | 145.77000000000001 |
| CLK_100M_MEZZ2_DP | 8337.48 | 5788.66 | 144.03 |
| CLK_100M_MEZZ2_R_DN | 161.27000000000001 | 188.73 | 85.45 |
| CLK_100M_MEZZ2_R_DP | 159.83000000000001 | 167.38 | 95.49 |
| CLK_100M_NIC_PE_DN | 7181.47 | 5433.51 | 132.16999999999999 |
| CLK_100M_NIC_PE_DP | 7182.05 | 5412.2 | 132.69999999999999 |
| CLK_100M_NIC_PE_R_DN | 161.59 | 197.35 | 81.88 |
| CLK_100M_NIC_PE_R_DP | 161.59 | 176.05 | 91.78 |
| CLK_100M_PCH_BMC_DN | 351.44 | 459.4 | 76.5 |
| CLK_100M_PCH_BMC_DP | 349.95 | 387.68 | 90.27 |
| CLK_100M_PCH_BMC_R_DN | 4889.72 | 5073.08 | 96.39 |
| CLK_100M_PCH_BMC_R_DP | 4889.08 | 5093.43 | 95.99 |
| CLK_100M_PCH_CPY_DN | 16889.490000000002 | 3370.04 | 501.17 |
| CLK_100M_PCH_CPY_DP | 16885.61 | 3291.04 | 513.08000000000004 |
| CLK_100M_PCH_DB1900_R_DN | 4506.54 | 2917.64 | 154.46 |
| CLK_100M_PCH_DB1900_R_DP | 4504.2299999999996 | 2915.64 | 154.49 |
| CLK_100M_PCH_SATAX_DN | 243.97 | 269.55 | 90.51 |
| CLK_100M_PCH_SATAX_DP | 246.96 | 258.55 | 95.52 |
| CLK_100M_PCH_SATA_DN | 324.26 | 277.54000000000002 | 116.83 |
| CLK_100M_PCH_SATA_DP | 325.17 | 279.2 | 116.47 |
| CLK_100M_PCH_XDP_DN | 276.62 | 309.18 | 89.47 |
| CLK_100M_PCH_XDP_DP | 275.88 | 236.68 | 116.56 |
| CLK_100M_PE_D_DN | 8379.24 | 2788.77 | 300.45999999999998 |
| CLK_100M_PE_D_DP | 8381.15 | 2767.45 | 302.85000000000002 |
| CLK_100M_PE_D_R_DN | 94 | 96.45 | 97.46 |
| CLK_100M_PE_D_R_DP | 94.13 | 96.78 | 97.26 |
| CLK_100M_RISER1_PE1_DN | 8717.25 | 3034.03 | 287.32 |
| CLK_100M_RISER1_PE1_DP | 8713.4500000000007 | 2953.66 | 295.01 |
| CLK_100M_RISER1_PE1_R_DN | 310.07 | 351.46 | 88.22 |
| CLK_100M_RISER1_PE1_R_DP | 310.13 | 372.81 | 83.19 |
| CLK_100M_RISER1_PE2_DN | 7279.44 | 2360.2600000000002 | 308.42 |
| CLK_100M_RISER1_PE2_DP | 7278 | 2438.37 | 298.48 |
| CLK_100M_RISER1_PE2_R_DN | 227.64 | 237.86 | 95.71 |
| CLK_100M_RISER1_PE2_R_DP | 227.51 | 259.16000000000003 | 87.79 |
| CLK_100M_RISER1_PE3_DN | 8425.2800000000007 | 4625.93 | 182.13 |
| CLK_100M_RISER1_PE3_DP | 8426.61 | 4546.9799999999996 | 185.32 |
| CLK_100M_RISER1_PE3_R_DN | 97.63 | 105.64 | 92.42 |
| CLK_100M_RISER1_PE3_R_DP | 97.65 | 85.4 | 114.34 |
| CLK_100M_RISER2_PE1_DN | 16735.78 | 14759.21 | 113.39 |
| CLK_100M_RISER2_PE1_DP | 16735.86 | 14774.32 | 113.28 |
| CLK_100M_RISER2_PE1_R_DN | 133.35 | 133.33000000000001 | 100.01 |
| CLK_100M_RISER2_PE1_R_DP | 133.19999999999999 | 154.68 | 86.12 |
| CLK_100M_XDP_DN | 12338.85 | 8453.4699999999993 | 145.96 |
| CLK_100M_XDP_DP | 12345.28 | 8476.32 | 145.63999999999999 |
| CLK_125_GTX_VD | 221.08 | 225.52 | 98.03 |
| CLK_14M_PCH | 603.79 | 773.52 | 78.06 |
| CLK_25M_CPLD | 3560.63 | 1646.29 | 216.28 |
| CLK_25M_CPLD_R | 78.7 | 96.43 | 81.61 |
| CLK_32K_SUSCLK_NGFF | 2667.6 | 2101.63 | 126.93 |
| CLK_32K_SUSCLK_PLD | 155.24 | 170.81 | 90.88 |
| CLK_32K_SUSCLK_PLD_R | 39.14 | 39.18 | 99.9 |
| CLK_33K_SUSCLK_PLD | 437.82 | 459.97 | 95.18 |
| CLK_33K_SUSCLK_PLD_R | 196.46 | 203.89 | 96.36 |
| CLK_33K_SUSCLK_PLD_R2 | 8247.4599999999991 | 3505.51 | 235.27 |
| CLK_33M_BMC1_LPC | 5295.73 | 4840.6000000000004 | 109.4 |
| CLK_33M_CPLD_LPC | 5224.08 | 4881.7299999999996 | 107.01 |
| CLK_33M_PCH | 2089.6799999999998 | 1450.74 | 144.04 |
| CLK_33M_PCH_BMC_LPC_R | 384.44 | 426.24 | 90.19 |
| CLK_33M_PCH_CPLD_R | 357.11 | 309.25 | 115.47 |
| CLK_33M_PCH_TPM_CONN_R | 280.56 | 330.63 | 84.86 |
| CLK_33M_PCH_TPM_R | 391.2 | 485.48 | 80.58 |
| CLK_33M_TPM_CONN | 3368.57 | 3057.72 | 110.17 |
| CLK_50M_BMC_MAC1 | 3454.79 | 3441 | 100.4 |
| CLK_50M_BMC_MAC2 | 5143.9799999999996 | 4585.53 | 112.18 |
| CLK_50M_BMC_MAC1_1 | 892.88 | 1036.54 | 86.14 |
| CLK_50M_BMC_MAC1_R | 128.28 | 165.77 | 77.38 |
| CLK_50M_BMC_MAC2_R | 146.26 | 128.74 | 113.61 |
| CLK_50M_BMC_NCSI | 3440.34 | 2737.85 | 125.66 |
| CLK_50M_BMC_NCSI_R | 208.09 | 189.2 | 109.99 |
| CLK_50M_NIC | 4650.3500000000004 | 4493.8999999999996 | 103.48 |
| CLK_50M_NIC_R | 166.91 | 200.08 | 83.42 |
| CLK_96M_PCH_DN | 316.04000000000002 | 238.1 | 132.72999999999999 |
| CLK_96M_PCH_DP | 316.64 | 249.35 | 126.99 |
| CLK_COMP_CKMNG | 236.79 | 288.44 | 82.09 |
| CLK_COMP_DB1900Z | 168.62 | 189.64 | 88.92 |
| COM1_DSR_2 | 98.42 | 123.02 | 80.010000000000005 |
| COM1_DTR_2 | 128.54 | 124.05 | 103.62 |
| COM1_RI_BMC | 8355.7099999999991 | 6629.82 | 126.03 |
| COM1_RTS_2 | 99.52 | 64.56 | 154.15 |
| COM1_RXD | 7193.39 | 5476.47 | 131.35 |
| COM1_TXD | 9033.26 | 5291.87 | 170.7 |
| COM2_RXD | 16531.740000000002 | 10060.81 | 164.32 |
| COM2_RXD_HDR | 170.82 | 221.04 | 77.28 |
| COM2_TXD | 15811.3 | 10015.68 | 157.87 |
| COM2_TXD_HDR | 170.03 | 183.34 | 92.74 |
| COM3_RXD | 24227.67 | 23075.62 | 104.99 |
| COM3_TXD | 23866.14 | 22883.14 | 104.3 |
| CPLD1_OK_HB | 6889.82 | 5707.47 | 120.72 |
| CPLD2_OK_HB | 9132.4500000000007 | 7117.41 | 128.31 |
| CPLD_ID | 172.15 | 159.66999999999999 | 107.81 |
| CPLD_LED_CATERR | 2881.01 | 2568.9699999999998 | 112.15 |
| CPLD_LED_CATERR_R | 302.10000000000002 | 366.27 | 82.48 |
| CPLD_PS_P5V_EN | 489.83 | 440.05 | 111.31 |
| CPU0_ERR2_N | 23077.3 | 15616.48 | 147.78 |
| CPU0_THERMTRIP_N_BMC | 2223.83 | 1971.08 | 112.82 |
| CPU0_THERMTRIP_OE_N | 148.22 | 72.08 | 205.63 |
| CPU1_ERR2_N | 18860.96 | 15098.84 | 124.92 |
| CPU1_THERMTRIP_N_BMC | 2152.2800000000002 | 1915.95 | 112.33 |
| CPU1_THERMTRIP_OE_N | 106 | 110.11 | 96.27 |
| CPU_CACHE_FLUSH_TRIGGER_N | 595.21 | 540.15 | 110.19 |
| CPU_DIMM_EVENT_LV_SHIFT | 212.48 | 81.17 | 261.77999999999997 |
| CSOUT_CMP | 305.07 | 234.45 | 130.12 |
| CSOUT_CMP_R | 201.9 | 47.49 | 425.14 |
| CURRENT_ALERT_CPLD_OUT | 503.11 | 347.08 | 144.94999999999999 |
| CURRENT_ALERT_N | 20608.09 | 18076.509999999998 | 114 |
| CURRENT_MODE | 360.6 | 295.94 | 121.85 |
| DACAV33 | 257.39999999999998 | 450.99 | 57.07 |
| DACRSET | 210.89 | 270.04000000000002 | 78.099999999999994 |
| DB1_OE10_N | 101.12 | 125.85 | 80.349999999999994 |
| DB1_OE9_N | 94.05 | 109.2 | 86.13 |
| DB_PRESENT_BMC_N | 2809.24 | 2843.01 | 98.81 |
| DB_PRESENT_N | 4220.66 | 4204.25 | 100.39 |
| DB_PRESENT_R_N | 747.08 | 721.5 | 103.54 |
| DDR_VREF | 832.06 | 995.25 | 83.6 |
| DMI_CPU0_PCH_RX_C_DN_0 | 7134.48 | 7219.87 | 98.82 |
| DMI_CPU0_PCH_RX_C_DN_1 | 7118.6 | 7251.9 | 98.16 |
| DMI_CPU0_PCH_RX_C_DN_2 | 7137.17 | 7350.01 | 97.1 |
| DMI_CPU0_PCH_RX_C_DN_3 | 7214.24 | 7446.7 | 96.88 |
| DMI_CPU0_PCH_RX_C_DP_0 | 7134.63 | 7243.81 | 98.49 |
| DMI_CPU0_PCH_RX_C_DP_1 | 7122.81 | 7275.96 | 97.9 |
| DMI_CPU0_PCH_RX_C_DP_2 | 7138.08 | 7374.01 | 96.8 |
| DMI_CPU0_PCH_RX_C_DP_3 | 7212.74 | 7470.7 | 96.55 |
| DMI_CPU0_PCH_RX_DN_0 | 350.69 | 351.05 | 99.9 |
| DMI_CPU0_PCH_RX_DN_1 | 386.82 | 426.46 | 90.71 |
| DMI_CPU0_PCH_RX_DN_2 | 418.02 | 478.93 | 87.28 |
| DMI_CPU0_PCH_RX_DN_3 | 641.01 | 673.27 | 95.21 |
| DMI_CPU0_PCH_RX_DP_0 | 351.17 | 354.11 | 99.17 |
| DMI_CPU0_PCH_RX_DP_1 | 387.19 | 429.4 | 90.17 |
| DMI_CPU0_PCH_RX_DP_2 | 420.58 | 481.93 | 87.27 |
| DMI_CPU0_PCH_RX_DP_3 | 642.13 | 667.82 | 96.15 |
| DMI_CPU0_PCH_TX_C_DN_0 | 876.88 | 843.18 | 104 |
| DMI_CPU0_PCH_TX_C_DN_1 | 758.64 | 852.7 | 88.97 |
| DMI_CPU0_PCH_TX_C_DN_2 | 935.42 | 895.73 | 104.43 |
| DMI_CPU0_PCH_TX_C_DN_3 | 861.11 | 924.1 | 93.18 |
| DMI_CPU0_PCH_TX_C_DP_0 | 874.03 | 836.49 | 104.49 |
| DMI_CPU0_PCH_TX_C_DP_1 | 760.74 | 845.63 | 89.96 |
| DMI_CPU0_PCH_TX_C_DP_2 | 936.34 | 829.03 | 112.94 |
| DMI_CPU0_PCH_TX_C_DP_3 | 860.95 | 894.69 | 96.23 |
| DMI_CPU0_PCH_TX_DN_0 | 6674.78 | 6845.29 | 97.51 |
| DMI_CPU0_PCH_TX_DN_1 | 6796.18 | 6876.73 | 98.83 |
| DMI_CPU0_PCH_TX_DN_2 | 6780.91 | 6919.4 | 98 |
| DMI_CPU0_PCH_TX_DN_3 | 6768.21 | 6915.45 | 97.87 |
| DMI_CPU0_PCH_TX_DP_0 | 6672.98 | 6858.72 | 97.29 |
| DMI_CPU0_PCH_TX_DP_1 | 6794.64 | 6894.48 | 98.55 |
| DMI_CPU0_PCH_TX_DP_2 | 6782.68 | 6938.8 | 97.75 |
| DMI_CPU0_PCH_TX_DP_3 | 6769.05 | 6938.88 | 97.55 |
| DMI_PCH_DMI_RCOMP | 60.81 | 28.37 | 214.35 |
| DRIVER_G | 552.46 | 346.4 | 159.49 |
| DRIVER_G_1 | 397.02 | 296.76 | 133.79 |
| DRIVER_G_2 | 45.11 | 115.79 | 38.96 |
| DRIVER_SHD_N | 227.8 | 75.459999999999994 | 301.88 |
| DRIVER_SHD_N_1 | 119.99 | 147.97 | 81.09 |
| DRIVER_SHD_N_2 | 62.39 | 66.290000000000006 | 94.11 |
| ENTEST1 | 206.04 | 158.99 | 129.59 |
| FAN0_PWM | 4523.5200000000004 | 3957.68 | 114.3 |
| FAN0_PWM_BMC | 32166.49 | 23788.81 | 135.22 |
| FAN0_PWM_CN | 520.5 | 591.44000000000005 | 88.01 |
| FAN0_TACH | 3664.02 | 3178.8 | 115.26 |
| FAN0_TACH0A | 4167.76 | 3315.62 | 125.7 |
| FAN0_TACH0A_BMC | 22910.19 | 19382.41 | 118.2 |
| FAN0_TACH0A_CN | 229.58 | 283.04000000000002 | 81.11 |
| FAN0_TACH_BMC | 22250.48 | 19667.96 | 113.13 |
| FAN0_TACH_CN | 229.09 | 279.04000000000002 | 82.1 |
| FAN1_EN_DRIVER | 481.14 | 309.45999999999998 | 155.47999999999999 |
| FAN1_EN_DRIVER_1 | 114.13 | 108.65 | 105.04 |
| FAN1_PWM | 203.99 | 185 | 110.27 |
| FAN1_PWM_BMC | 33226.400000000001 | 23852.81 | 139.30000000000001 |
| FAN1_PWM_CN | 1814.02 | 1654.6 | 109.64 |
| FAN1_TACH | 7707.14 | 6972.58 | 110.54 |
| FAN1_TACH1A | 8414.7800000000007 | 7304.22 | 115.2 |
| FAN1_TACH1A_BMC | 23989.97 | 20036.28 | 119.73 |
| FAN1_TACH1A_CN | 191.39 | 242.57 | 78.900000000000006 |
| FAN1_TACH_BMC | 21317.72 | 19432.18 | 109.7 |
| FAN1_TACH_CN | 324.89999999999998 | 400.17 | 81.19 |
| FAN_PWR_PG | 98.56 | 69.86 | 141.08000000000001 |
| FET_SMB_HOST_CLK | 149.54 | 179.45 | 83.33 |
| FET_SMB_HOST_DATA | 162.75 | 157.5 | 103.34 |
| FILTER_P1V05_XCK_DCB | 100.45 | 63.3 | 158.69 |
| FLA_CS | 421.28 | 475.18 | 88.66 |
| FLA_CS_R | 3282.19 | 2568.0300000000002 | 127.81 |
| FM_ADR_BMC_TRIGGER | 8706.73 | 5955.91 | 146.19 |
| FM_ADR_COMPLETE | 13080.56 | 9375.09 | 139.52000000000001 |
| FM_ADR_COMPLETE_CPLD_SAVE | 6683.79 | 5550.46 | 120.42 |
| FM_ADR_COMPLETE_R | 467.18 | 433.02 | 107.89 |
| FM_ADR_COMPLETE_SAVE | 1269.2 | 1063.98 | 119.29 |
| FM_ADR_COMPLETE_SAVE_N | 8229.59 | 5525.77 | 148.93 |
| FM_ADR_COMPLETE_SAVE_R_N | 131.18 | 79 | 166.05 |
| FM_ADR_TRIGGER_EN | 8700.99 | 5995.28 | 145.13 |
| FM_ADR_TRIGGER_N | 312.8 | 129.1 | 242.3 |
| FM_BIOS_POST_CMPLT_N | 6571.94 | 5867.78 | 112 |
| FM_BIOS_RCVR_BOOT_N | 1634.66 | 1637.04 | 99.85 |
| FM_BMC_ADR_COMPLETE | 580.57000000000005 | 376.72 | 154.11000000000001 |
| FM_BMC_LAN1_DISABLE_N | 3245.17 | 2957.31 | 109.73 |
| FM_BMC_PCH_SCI_LPC_N | 5492.36 | 4960.84 | 110.71 |
| FM_BMC_PWRBTN_OUT_N | 6964.72 | 4360.07 | 159.74 |
| FM_BMC_READY_N | 14581.37 | 11121.06 | 131.11000000000001 |
| FM_BMC_SMI_ACTIVE_N | 2242.8000000000002 | 1414.51 | 158.56 |
| FM_CATERR_DLY | 278.02 | 125.2 | 222.06 |
| FM_CATERR_DLY_BUF_N | 151.47999999999999 | 60.4 | 250.79 |
| FM_CATERR_DLY_FF_Q | 119.67 | 92.23 | 129.75 |
| FM_CATERR_DLY_FF_Q_R | 182.49 | 200.19 | 91.16 |
| FM_CATERR_DLY_N | 320.45999999999998 | 214.96 | 149.08000000000001 |
| FM_CATERR_RC_N | 1463.08 | 1551.98 | 94.27 |
| FM_CATERR_RC_R_N | 319.12 | 216.01 | 147.72999999999999 |
| FM_CPLD_ADR_COMPLETE | 341.87 | 373.13 | 91.62 |
| FM_CPLD_BMC_THERMTRIP_N | 7867.37 | 5786.63 | 135.96 |
| FM_CPLD_PCH_CATERR_MSMI_N | 3287.37 | 2442.86 | 134.57 |
| FM_CPU0_BDX_PRSNT_LVT3_N | 14568.16 | 10838.18 | 134.41999999999999 |
| FM_CPU0_ERR0_LVT3_N | 244.98 | 283.18 | 86.51 |
| FM_CPU0_ERR0_LVT3_N_R | 265.98 | 297.3 | 89.46 |
| FM_CPU0_ERR0_LVT3_R_N | 263.01 | 185.15 | 142.05000000000001 |
| FM_CPU0_ERR1_LVT3_N | 314.57 | 254.79 | 123.46 |
| FM_CPU0_ERR1_LVT3_N_R | 579.19000000000005 | 391.5 | 147.94 |
| FM_CPU0_ERR1_LVT3_R_N | 113.82 | 125.75 | 90.52 |
| FM_CPU0_ERR2_LVT3_N | 241.13 | 261.75 | 92.12 |
| FM_CPU0_ERR2_LVT3_N_R | 434.75 | 381.3 | 114.02 |
| FM_CPU0_ERR2_LVT3_R_N | 212.41 | 28.37 | 748.73 |
| FM_CPU0_FIVR_FAULT_CO_D_N | 210.77 | 237.63 | 88.69 |
| FM_CPU0_FIVR_FAULT_LVC3_N | 733.18 | 474.64 | 154.47 |
| FM_CPU0_FIVR_FAULT_LVT3 | 6168.74 | 5267.5 | 117.11 |
| FM_CPU0_FIVR_FAULT_LVT3_N | 4407.1099999999997 | 3239.42 | 136.05000000000001 |
| FM_CPU0_FIVR_FAULT_LVT3_R_N | 124.24 | 128.69999999999999 | 96.53 |
| FM_CPU0_PROCHOT_LVT3_N | 11572.19 | 9394.43 | 123.18 |
| FM_CPU0_PROCHOT_LVT3_R_N | 212.24 | 245.1 | 86.59 |
| FM_CPU0_PWRGD_PORST | 434.09 | 272.16000000000003 | 159.5 |
| FM_CPU0_SKTOCC_BMC_LVT3_N | 4665.32 | 3988.16 | 116.98 |
| FM_CPU0_SKTOCC_LVT3_N | 18782.009999999998 | 11187.93 | 167.88 |
| FM_CPU0_THERMTRIP_LATCH_LVC3_N | 164.36 | 76.739999999999995 | 214.18 |
| FM_CPU0_THERMTRIP_LVC3_N | 3738.29 | 3638.35 | 102.75 |
| FM_CPU0_THERMTRIP_LVC3_N_R | 972.91 | 970.88 | 100.21 |
| FM_CPU0_THERMTRIP_LVT3_N | 6711.74 | 5735.7 | 117.02 |
| FM_CPU0_THERMTRIP_LVT3_R_N | 137.66 | 171.9 | 80.08 |
| FM_CPU1_BDX_PRSNT_LVT3_N | 15019.89 | 12500.49 | 120.15 |
| FM_CPU1_ERR0_LVT3_N | 130.22 | 119.3 | 109.16 |
| FM_CPU1_ERR0_LVT3_N_R | 539.15 | 607.25 | 88.79 |
| FM_CPU1_ERR0_LVT3_R_N | 153.75 | 183.82 | 83.64 |
| FM_CPU1_ERR1_LVT3_N | 117.52 | 129.57 | 90.7 |
| FM_CPU1_ERR1_LVT3_N_R | 104.65 | 109.1 | 95.92 |
| FM_CPU1_ERR1_LVT3_R_N | 180.02 | 199.15 | 90.39 |
| FM_CPU1_ERR2_LVT3_N | 173.43 | 206.36 | 84.04 |
| FM_CPU1_ERR2_LVT3_N_R | 256.07 | 212.9 | 120.28 |
| FM_CPU1_ERR2_LVT3_R_N | 108.59 | 122.36 | 88.74 |
| FM_CPU1_FIVR_FAULT_CO_D_N | 416.43 | 338.68 | 122.96 |
| FM_CPU1_FIVR_FAULT_LVC3_N | 135.82 | 108.86 | 124.76 |
| FM_CPU1_FIVR_FAULT_LVT3 | 17909.830000000002 | 11043.5 | 162.18 |
| FM_CPU1_FIVR_FAULT_LVT3_N | 4536.43 | 3360.26 | 135 |
| FM_CPU1_FIVR_FAULT_LVT3_R_N | 171.74 | 175.44 | 97.89 |
| FM_CPU1_PROCHOT_LVT3_N | 23667.42 | 15246.31 | 155.22999999999999 |
| FM_CPU1_PROCHOT_LVT3_R_N | 157.22 | 160.22 | 98.13 |
| FM_CPU1_SKTOCC_BMC_LVT3_N | 5821.34 | 4127.0600000000004 | 141.05000000000001 |
| FM_CPU1_SKTOCC_LVT3_N | 17734.2 | 12714.71 | 139.47999999999999 |
| FM_CPU1_THERMTRIP_LATCH_LVC3_N | 138.06 | 148.9 | 92.72 |
| FM_CPU1_THERMTRIP_LVC3_N | 3060.15 | 2663.11 | 114.91 |
| FM_CPU1_THERMTRIP_LVC3_N_R | 652.80999999999995 | 478.62 | 136.38999999999999 |
| FM_CPU1_THERMTRIP_LVT3_N | 18232.41 | 12682.28 | 143.76 |
| FM_CPU1_THERMTRIP_LVT3_R_N | 160.59 | 169.02 | 95.01 |
| FM_CPU_BMC_ERR0_CO_N | 1940.04 | 1817.37 | 106.75 |
| FM_CPU_CATERR_LVT3_N | 11900.74 | 10921.85 | 108.96 |
| FM_CPU_CATERR_LVT3_R_N | 180.52 | 187.3 | 96.38 |
| FM_CPU_DIMM_EVENT_CO_N | 43447.85 | 28744.880000000001 | 151.15 |
| FM_CPU_ERR0_CO_N | 16415.34 | 13870.46 | 118.35 |
| FM_CPU_ERR1_CO_N | 20482.740000000002 | 15338.09 | 133.54 |
| FM_CPU_MSMI_LVT3_BMC_N | 21782.25 | 17720.48 | 122.92 |
| FM_CPU_MSMI_LVT3_R_N | 200.21 | 206.42 | 96.99 |
| FM_CPU_PROCHOT_N | 400.23 | 241.65 | 165.63 |
| FM_CPU_THERMTRIP_PORST | 497.97 | 202.62 | 245.77 |
| FM_ERR1_DLY_N | 3300.32 | 3261.19 | 101.2 |
| FM_GPIO_ALERT_BUF_EN | 4337.3999999999996 | 3453.12 | 125.61 |
| FM_GPIO_ALERT_BUF_PLD | 286.22000000000003 | 173.29 | 165.17 |
| FM_LA_TRIGGER_N_PLD_TDO | 1925.47 | 1711.08 | 112.53 |
| FM_LVC1_THERMTRIP_N | 839.8 | 828.96 | 101.31 |
| FM_LVC3_CP | 168.32 | 166.63 | 101.01 |
| FM_LVC3_CPU0_PWRGD | 700.81 | 691.02 | 101.42 |
| FM_LVC3_CPU0_PWRGD_R | 134.01 | 136.57 | 98.13 |
| FM_LVC3_CPU1_PWRGD | 486.01 | 420.16 | 115.67 |
| FM_LVC3_CPU1_PWRGD_R | 117.15 | 98.89 | 118.47 |
| FM_LVC3_CPU_CATERR_N | 1517.11 | 1667.62 | 90.97 |
| FM_LVC3_D | 280.23 | 211.88 | 132.26 |
| FM_LVC3_THERMTRIP_DLY | 193.84 | 258.75 | 74.92 |
| FM_LVC3_THERMTRIP_DLY_R | 3161.31 | 2285.65 | 138.31 |
| FM_MEM_THERM_EVENT_LVT3_N | 5765.93 | 4286.17 | 134.52000000000001 |
| FM_MEZZ_PRSNT_N | 2767.7 | 2837.59 | 97.54 |
| FM_ME_CMM_N | 126.09 | 75.760000000000005 | 166.43 |
| FM_ME_RCVR_N | 2017.78 | 1432.46 | 140.86000000000001 |
| FM_MGPIO14 | 256.18 | 240.2 | 106.65 |
| FM_MGPIO15 | 157.68 | 153.88 | 102.47 |
| FM_MGPIO16 | 279.95 | 271.88 | 102.97 |
| FM_MGPIO17 | 163.82 | 175.24 | 93.48 |
| FM_NMI_EVENT_N_NOA_CLK2 | 9883.9 | 6699.63 | 147.53 |
| FM_P3V3_CPLD_EN | 4917.32 | 4532.8599999999997 | 108.48 |
| FM_PASSWORD_CLEAR_N | 495.4 | 439.69 | 112.67 |
| FM_PCH_BMC_THERMTRIP_N | 4699.1400000000003 | 2996.85 | 156.80000000000001 |
| FM_PCH_BMC_THERMTRIP_R_N | 582.13 | 591.97 | 98.34 |
| FM_PCH_LAN1_DISABLE_N | 6470.89 | 6203.92 | 104.3 |
| FM_PCH_LDRQ_N | 67.099999999999994 | 40.83 | 164.34 |
| FM_PCH_PRSNT_CO_N | 3563.43 | 3396.57 | 104.91 |
| FM_PCIE_SLOT_CPRSNT1_N | 6377.37 | 5698.4 | 111.92 |
| FM_PCIE_SLOT_CPRSNT2_N | 4730.6400000000003 | 5134.71 | 92.13 |
| FM_PCIE_SLOT_CPRSNT3_N | 5856.27 | 4540.91 | 128.97 |
| FM_PCIE_SLOT_CPRSNT4_N | 4027.86 | 3210.75 | 125.45 |
| FM_PCIE_SLOT_CPRSNT5_N | 3962.33 | 2950.87 | 134.28 |
| FM_PCIE_SLOT_CPRSNT6_N | 4394.2 | 3328.18 | 132.03 |
| FM_PERST_SRC_LVT3 | 263.45 | 225.2 | 116.99 |
| FM_PLD_CLK_EN | 1091.78 | 1185.0999999999999 | 92.13 |
| FM_PLD_DEBUG1 | 285.35000000000002 | 288.05 | 99.06 |
| FM_PLD_DEBUG2 | 174.89 | 184.01 | 95.04 |
| FM_PLD_DEBUG3 | 213.46 | 230.5 | 92.61 |
| FM_PLD_DEBUG4 | 982.1 | 855.7 | 114.77 |
| FM_PLD_DEBUG5 | 252.75 | 311.63 | 81.099999999999994 |
| FM_PLD_DEBUG1_R | 128.57 | 160.24 | 80.239999999999995 |
| FM_PLD_DEBUG2_R | 323.35000000000002 | 193.05 | 167.49 |
| FM_PLD_DEBUG3_R | 160.9 | 97.54 | 164.96 |
| FM_PLD_DEBUG4_R | 175.88 | 66.5 | 264.49 |
| FM_PLD_DEBUG5_R | 143.82 | 167.95 | 85.63 |
| FM_PLD_DEBUG_MODE_N | 468.71 | 294.72000000000003 | 159.03 |
| FM_PLD_RESET_N | 269.2 | 295.27 | 91.17 |
| FM_PLD_TSALL | 199.93 | 231.18 | 86.48 |
| FM_PMBUS_ALERT_BUF_EN | 4731.93 | 4565.68 | 103.64 |
| FM_PMBUS_ALERT_BUF_PLD | 240.1 | 175.46 | 136.84 |
| FM_PS_EN | 26931 | 24464.97 | 110.08 |
| FM_PS_EN_R | 245.38 | 193.84 | 126.59 |
| FM_QPI_SLOW_MODE_N | 489 | 489.78 | 99.84 |
| FM_SLPA_N | 823.11 | 708.79 | 116.13 |
| FM_SLPS3_N | 15234.33 | 13532.55 | 112.58 |
| FM_SLPS3_N_CPLD | 446.59 | 510.83 | 87.43 |
| FM_SLPS4_N | 7438.8 | 7408.49 | 100.41 |
| FM_SMI_ACTIVE_N | 8980.7199999999993 | 5595.54 | 160.5 |
| FM_SYS_THROTTLE_LVC3_N | 11862.63 | 7484.3 | 158.5 |
| FM_THERMTRIP_CO_N | 5380.95 | 5245.91 | 102.57 |
| FM_THROTTLE_AND_N | 326.92 | 123.45 | 264.82 |
| FM_THROTTLE_N | 261.94 | 176.96 | 148.02000000000001 |
| FM_THROTTLE_N_BMC | 6353.42 | 4797.95 | 132.41999999999999 |
| FM_USB3_P0_EN_N | 5608.53 | 4924.95 | 113.88 |
| FM_USB3_P1_EN_N | 5206.0200000000004 | 4763.9399999999996 | 109.28 |
| FM_VCC_MAIN_EN | 2708.61 | 2597.16 | 104.29 |
| FM_VPP_MEM_ABCD_EN | 14557.43 | 11937.02 | 121.95 |
| FM_VPP_MEM_EFGH_EN | 26466.6 | 16103.51 | 164.35 |
| FM_XDP_HOOK1_SEL | 183.48 | 196.26 | 93.49 |
| FP_BTN_RESET_N2 | 1161.43 | 941.06 | 123.42 |
| FP_PWRBTN | 130.96 | 135.06 | 96.97 |
| FP_PWRBTN_N | 1905.06 | 1840.33 | 103.52 |
| FP_PWRBTN_R | 137.08000000000001 | 125.66 | 109.09 |
| FP_PWRBTN_RC_N | 602.29999999999995 | 703.84 | 85.57 |
| FP_PWR_BTN_N | 10397.5 | 7063.18 | 147.21 |
| FP_RSTBTN | 123.94 | 133.78 | 92.64 |
| FP_RSTBTN_N | 422.14 | 455.68 | 92.64 |
| FP_RSTBTN_R | 610.99 | 390.78 | 156.35 |
| FP_RSTBTN_RC_N | 2161.66 | 1982.91 | 109.01 |
| GTL2034_VREF | 148.63999999999999 | 154.5 | 96.21 |
| HDD_LED_SATA_ACT_N | 1648.02 | 1794.53 | 91.84 |
| HIGH_HEX_0 | 3255.11 | 2973.33 | 109.48 |
| HIGH_HEX_1 | 3039.04 | 2741.93 | 110.84 |
| HIGH_HEX_2 | 3377.8 | 2954.91 | 114.31 |
| HIGH_HEX_3 | 2935.73 | 2926.8 | 100.31 |
| HOST_SLOT1_SCL | 195.52 | 199.62 | 97.95 |
| HOST_SLOT1_SDA | 127.77 | 119.25 | 107.15 |
| H_CPU0_CATERR_G_N | 5389.07 | 5445.25 | 98.97 |
| H_CPU0_ERR0_G_N | 3987.03 | 4300.46 | 92.71 |
| H_CPU0_ERR1_G_N | 3919.3 | 4435.46 | 88.36 |
| H_CPU0_ERR2_G_N | 4073.47 | 4347.8599999999997 | 93.69 |
| H_CPU0_FAST_WAKE_G_N | 2755.22 | 3101.6 | 88.83 |
| H_CPU0_FIVR_FAULT_G | 4101.83 | 4056.49 | 101.12 |
| H_CPU0_MEMAB_MEMHOT_BMC_LVT3_N | 9867.39 | 6490.41 | 152.03 |
| H_CPU0_MEMAB_MEMHOT_G_N | 9986.24 | 7650.37 | 130.53 |
| H_CPU0_MEMAB_MEMHOT_LVT3_N | 143.97 | 99.12 | 145.24 |
| H_CPU0_MEMAB_MEMHOT_LVT3_R_N | 261.54000000000002 | 315.08 | 83.01 |
| H_CPU0_MEMCD_MEMHOT_BMC_LVT3_N | 9654.35 | 6288.92 | 153.51 |
| H_CPU0_MEMCD_MEMHOT_G_N | 11204.07 | 7618.36 | 147.07 |
| H_CPU0_MEMCD_MEMHOT_LVT3_N | 86.03 | 99.12 | 86.79 |
| H_CPU0_MEMCD_MEMHOT_LVT3_R_N | 274.88 | 333.48 | 82.43 |
| H_CPU0_MSMI_G_N | 563.65 | 734.54 | 76.739999999999995 |
| H_CPU0_PROCHOT_G_N | 11595.57 | 8151.7 | 142.25 |
| H_CPU0_THERMTRIP_G_N | 5187.71 | 5125.6000000000004 | 101.21 |
| H_CPU1_CATERR_G_N | 9865.58 | 10840.46 | 91.01 |
| H_CPU1_ERR0_G_N | 2028.29 | 2116.31 | 95.84 |
| H_CPU1_ERR1_G_N | 1877.56 | 2179.7399999999998 | 86.14 |
| H_CPU1_ERR2_G_N | 2118.94 | 2372.85 | 89.3 |
| H_CPU1_FAST_WAKE_G_N | 4241.5600000000004 | 3948.34 | 107.43 |
| H_CPU1_FIVR_FAULT_G | 2646.28 | 2946.48 | 89.81 |
| H_CPU1_MEMEF_MEMHOT_BMC_LVT3_N | 11180.53 | 6305.01 | 177.33 |
| H_CPU1_MEMEF_MEMHOT_G_N | 17432.400000000001 | 10064.83 | 173.2 |
| H_CPU1_MEMEF_MEMHOT_LVT3_N | 84.58 | 99.14 | 85.31 |
| H_CPU1_MEMEF_MEMHOT_LVT3_R_N | 295.62 | 329.17 | 89.81 |
| H_CPU1_MEMGH_MEMHOT_BMC_LVT3_N | 10585.69 | 6324.44 | 167.38 |
| H_CPU1_MEMGH_MEMHOT_G_N | 18148.419999999998 | 11900.58 | 152.5 |
| H_CPU1_MEMGH_MEMHOT_LVT3_N | 139 | 99.42 | 139.81 |
| H_CPU1_MEMGH_MEMHOT_LVT3_R_N | 328.4 | 346.85 | 94.68 |
| H_CPU1_MSMI_G_N | 1021.78 | 966.59 | 105.71 |
| H_CPU1_PROCHOT_G_N | 25811.64 | 15733.98 | 164.05 |
| H_CPU1_THERMTRIP_G_N | 2518.2600000000002 | 1980.37 | 127.16 |
| H_CPU_CATERR_G_N | 565.46 | 455.3 | 124.19 |
| H_CPU_MSMI_G_N | 5855.7 | 3761.8 | 155.66 |
| H_LVT3_CPU0_PROCHOT_OD_N | 242.33 | 298.23 | 81.260000000000005 |
| H_LVT3_CPU1_PROCHOT_OD_N | 173.8 | 183.56 | 94.68 |
| H_PM_SYNC_G | 15776.71 | 12861.78 | 122.66 |
| I210_CBOT | 156.81 | 105.43 | 148.72999999999999 |
| I210_CTOP | 110.94 | 129.49 | 85.68 |
| IRQ_BMC_PCH_NMI_NOA1_CLK | 4555.41 | 3470.97 | 131.24 |
| IRQ_BMC_PCH_NMI_NOA1_CLK_MUX | 740.58 | 610.91 | 121.23 |
| IRQ_BMC_PCH_NMI_R | 165.95 | 144.49 | 114.86 |
| IRQ_BMC_PCH_NMI_STBY | 3199.17 | 2676.84 | 119.51 |
| IRQ_CPU0_01_MEMHOT_D | 179.57 | 95.04 | 188.94 |
| IRQ_CPU0_23_MEMHOT_D | 224.68 | 172.25 | 130.44 |
| IRQ_CPU0_VRHOT_D | 2197.9699999999998 | 2385.6799999999998 | 92.13 |
| IRQ_CPU1_01_MEMHOT_D | 179.01 | 141.46 | 126.54 |
| IRQ_CPU1_23_MEMHOT_D | 266.14 | 215.38 | 123.57 |
| IRQ_CPU1_VRHOT_D | 15826.03 | 13415.02 | 117.97 |
| IRQ_CPU_CATERR_DLY | 2973.11 | 1748.18 | 170.07 |
| IRQ_IBMC_PCH_SMI | 448.53 | 384.81 | 116.56 |
| IRQ_IBMC_PCH_SMI_LPC_N | 5557.64 | 5452.83 | 101.92 |
| IRQ_LVC3_WAKE_DLY_EN | 166.61 | 138.18 | 120.58 |
| IRQ_LVC3_WAKE_EN | 774.74 | 647.70000000000005 | 119.61 |
| IRQ_LVC3_WAKE_N | 12443.04 | 10173.42 | 122.31 |
| IRQ_LVC3_WAKE_N_210 | 253.35 | 250.18 | 101.27 |
| IRQ_LVC3_WAKE_N_MSATA | 253.64 | 100.37 | 252.71 |
| IRQ_LVC3_WAKE_N_NGFF | 306.55 | 150.80000000000001 | 203.28 |
| IRQ_LVC3_WOL_N | 259.45999999999998 | 227.16 | 114.22 |
| IRQ_LVC3_WOL_N1 | 110.97 | 115.06 | 96.44 |
| IRQ_LVC3_WOL_N2 | 541.79 | 480.72 | 112.7 |
| IRQ_MID_PMBUS_ALERT_N | 21227.279999999999 | 17122.32 | 123.97 |
| IRQ_PVCCIN_CPU0_VRHOT_LVT3_N | 12359.69 | 8331.5499999999993 | 148.35 |
| IRQ_PVCCIN_CPU1_VRHOT_LVT3_N | 26166.84 | 18903.28 | 138.41999999999999 |
| IRQ_PVDDQ_AB_VRHOT_LVT3_N | 14362.13 | 11927.36 | 120.41 |
| IRQ_PVDDQ_CD_VRHOT_LVT3_N | 5713.23 | 4393.92 | 130.03 |
| IRQ_PVDDQ_EF_VRHOT_LVT3_N | 22752.55 | 13881.28 | 163.91 |
| IRQ_PVDDQ_GH_VRHOT_LVT3_N | 23218.76 | 16203.69 | 143.29 |
| IRQ_SERIAL | 12779.17 | 9519.23 | 134.25 |
| IRQ_SML0_ALERT_N | 3141.78 | 2860.04 | 109.85 |
| IRQ_SML0_ALERT_R_N | 6348.31 | 5141.72 | 123.47 |
| IRQ_SML1_PMBUS_ALERT_BUF_N | 11611.99 | 6687.25 | 173.64 |
| IRQ_SML1_PMBUS_ALERT_N | 29179.16 | 23370.09 | 124.86 |
| IRQ_SML1_PMBUS_ALERT_N_PLD | 335.9 | 352.44 | 95.31 |
| JTAG_PLD1_TCK | 6312.88 | 4539.9799999999996 | 139.05000000000001 |
| JTAG_PLD1_TDI | 6632.55 | 4394.99 | 150.91 |
| JTAG_PLD1_TDO | 6201.1 | 4200.29 | 147.63 |
| JTAG_PLD1_TMS | 6457.21 | 4856.7299999999996 | 132.94999999999999 |
| JTAG_PLD_TCK | 3247.34 | 2673.2 | 121.48 |
| JTAG_PLD_TDI | 3221.28 | 2964.51 | 108.66 |
| JTAG_PLD_TDO | 3042.78 | 3237.21 | 93.99 |
| JTAG_PLD_TMS | 3122.15 | 2769.25 | 112.74 |
| LAN1_51 | 146.04 | 122.36 | 119.35 |
| LAN1_56 | 100.87 | 17.989999999999998 | 560.72 |
| LAN_MAIN_PWR_OK | 135.41999999999999 | 60.03 | 225.59 |
| LAN_SE_RSET | 160.58000000000001 | 176.19 | 91.14 |
| LAN_SMB_ALERT_N | 9698.16 | 7913.25 | 122.56 |
| LAN_SMB_ALERT_N_I210 | 287.52 | 212.94 | 135.03 |
| LAN_SMB_ALERT_N_MEZZ | 216.8 | 134.07 | 161.71 |
| LAN_SMB_ALERT_N_PCIE | 126.51 | 145.91 | 86.71 |
| LAN_SMB_CLK | 18286.89 | 9166.74 | 199.49 |
| LAN_SMB_CLK_I210 | 212.63 | 70.72 | 300.67 |
| LAN_SMB_CLK_MEZZ | 128.4 | 144.38999999999999 | 88.92 |
| LAN_SMB_CLK_PCIE | 405.9 | 193.1 | 210.2 |
| LAN_SMB_DAT | 17372.47 | 9063.99 | 191.66 |
| LAN_SMB_DAT_I210 | 265.20999999999998 | 234.91 | 112.9 |
| LAN_SMB_DAT_MEZZ | 226.47 | 156.46 | 144.74 |
| LAN_SMB_DAT_PCIE | 427.08 | 412.89 | 103.44 |
| LED_DEBUG1 | 103.81 | 64.55 | 160.82 |
| LED_DEBUG2 | 88.31 | 92.77 | 95.19 |
| LED_DEBUG3 | 119.32 | 73.67 | 161.96 |
| LED_DEBUG4 | 189.45 | 202.5 | 93.56 |
| LED_DEBUG5 | 401.86 | 393.5 | 102.13 |
| LED_DEBUG1_R | 299.8 | 38.07 | 787.49 |
| LED_DEBUG2_R | 149.59 | 121.08 | 123.55 |
| LED_DEBUG3_R | 304.04000000000002 | 77.5 | 392.31 |
| LED_DEBUG4_R | 191.07 | 106.05 | 180.17 |
| LED_DEBUG5_R | 274.10000000000002 | 367.69 | 74.55 |
| LED_MDI0_100M_1G_N | 187.66 | 197.02 | 95.25 |
| LED_MDI0_100M_N | 2512.19 | 2349.7199999999998 | 106.91 |
| LED_MDI0_100M_N_R | 262.64 | 275.52 | 95.33 |
| LED_MDI0_1G_N | 2440.98 | 2103.9699999999998 | 116.02 |
| LED_MDI0_1G_N_R | 214.79 | 216.56 | 99.18 |
| LED_MDI0_ACT | 308.33999999999997 | 351.1 | 87.82 |
| LED_MDI0_LINK_N | 3014.76 | 2676.96 | 112.62 |
| LED_PWRBLINK_BMC | 5252.84 | 3450.57 | 152.22999999999999 |
| LED_PWRBLINK_SSB_R | 250.6 | 178.65 | 140.28 |
| LED_PWRSW | 3781.59 | 3484.89 | 108.51 |
| LED_PWR_SI_BMC_R_N | 385.27 | 437.42 | 88.08 |
| LED_SATA_ACT_N | 8302.7099999999991 | 6420.39 | 129.32 |
| LED_SATA_ACT_R_N | 594.88 | 703.43 | 84.57 |
| LED_SSATA_ACT_N | 6266.43 | 6416.7 | 97.66 |
| LOW_HEX_0 | 3310.87 | 2831.18 | 116.94 |
| LOW_HEX_1 | 2979.09 | 2820.56 | 105.62 |
| LOW_HEX_2 | 3330.3 | 2800.98 | 118.9 |
| LOW_HEX_3 | 2846.33 | 2682.87 | 106.09 |
| LPCRST_1 | 491.95 | 449.73 | 109.39 |
| LPC_FRAME_N | 8801.8700000000008 | 8792.16 | 100.11 |
| LPC_LAD0 | 6250.64 | 6252.22 | 99.97 |
| LPC_LAD1 | 6239.72 | 6149.85 | 101.46 |
| LPC_LAD2 | 6477.87 | 6230.04 | 103.98 |
| LPC_LAD3 | 6223.6 | 6228.58 | 99.92 |
| MATED_IN_N | 4170.96 | 3015.84 | 138.30000000000001 |
| MATED_IN_N_D | 69.41 | 75.14 | 92.37 |
| MATED_IN_N_Q | 251.78 | 180.47 | 139.52000000000001 |
| MATED_IN_N_R | 1843.3 | 1471.11 | 125.3 |
| MB0_12V_CTRL_GATE1 | 334.14 | 212.43 | 157.29 |
| MB0_12V_CTRL_GATE2 | 537.49 | 522.99 | 102.77 |
| MB0_412W | 201.91 | 243.5 | 82.92 |
| MB0_575W | 90.16 | 92.5 | 97.47 |
| MB0_CM_ADR1_R | 167.89 | 135.94999999999999 | 123.49 |
| MB0_CM_ADR2_R | 132.31 | 159.26 | 83.08 |
| MB0_CM_FAULT_N_R | 24049.200000000001 | 21039.119999999999 | 114.31 |
| MB0_CM_GATE | 685.7 | 488.91 | 140.25 |
| MB0_CM_GATE_R | 156.69 | 160.46 | 97.65 |
| MB0_CM_OV_R | 488.05 | 378.7 | 128.88 |
| MB0_CM_SENSE_N | 1295.6099999999999 | 1211.28 | 106.96 |
| MB0_CM_SENSE_P | 1307.76 | 1250.07 | 104.61 |
| MB0_CM_SENSE_R1_N | 278.32 | 82.11 | 338.96 |
| MB0_CM_SENSE_R1_P | 301.42 | 87.11 | 346.02 |
| MB0_CM_SENSE_R2_N | 240.02 | 89.51 | 268.14 |
| MB0_CM_SENSE_R2_P | 260.97000000000003 | 91.31 | 285.8 |
| MB0_CM_UV_R | 592.04999999999995 | 485.33 | 121.99 |
| MB0_CM_VOUT_R | 170.25 | 147.37 | 115.53 |
| MB0_CSOUT_N | 188.53 | 200.05 | 94.24 |
| MB0_CURMON_ALERT1_R_N | 148.01 | 181.92 | 81.36 |
| MB0_CURMON_ALERT2_R_N | 233.33 | 255.63 | 91.28 |
| MB0_HS_ENABLE | 286.87 | 250.85 | 114.36 |
| MB0_ISET_R | 301.20999999999998 | 332.34 | 90.63 |
| MB0_ISTART_R | 240.27 | 312.19 | 76.959999999999994 |
| MB0_MO_N | 321.02999999999997 | 132.59 | 242.13 |
| MB0_MO_P | 467.43 | 191.2 | 244.47 |
| MB0_P12V_HS | 166.84 | 80.12 | 208.24 |
| MB0_P12V_MAIN_R | 317.01 | 820.4 | 38.64 |
| MB0_P12V_PWGIN_R | 207.92 | 141.04 | 147.41999999999999 |
| MB0_P12V_PWRGOOD | 22926.03 | 18467.87 | 124.14 |
| MB0_PMBUS_PCH_SML1CLK_R | 229.78 | 253.16 | 90.77 |
| MB0_PMBUS_PCH_SML1DATA_R | 278.95999999999998 | 316.22000000000003 | 88.22 |
| MB0_PSET_R | 235.3 | 203.04 | 115.89 |
| MB0_RETRY_R | 152.75 | 113.13 | 135.02000000000001 |
| MB0_SPISS_PD | 215.58 | 236.06 | 91.32 |
| MB0_TEMP | 1145.83 | 883.26 | 129.72999999999999 |
| MB0_TIME_R | 1245.6400000000001 | 1102.23 | 113.01 |
| MB0_VCAP_R | 880.63 | 799.14 | 110.2 |
| MB_ON_N | 1226.3399999999999 | 1219.01 | 100.6 |
| MB_ON_N_R | 211.75 | 117 | 180.98 |
| MB_SLOT_ID0 | 23593.43 | 17946.509999999998 | 131.47 |
| MB_SLOT_ID1 | 19927.810000000001 | 17785.009999999998 | 112.05 |
| MB_SLOT_ID2 | 7454.06 | 6089.99 | 122.4 |
| MB_SLOT_ID0_R | 826.15 | 858.88 | 96.19 |
| MB_SLOT_ID1_R | 907.48 | 853.77 | 106.29 |
| MB_SLOT_ID2_R | 20414.43 | 18090.349999999999 | 112.85 |
| MEMA_0 | 606.84 | 550.27 | 110.28 |
| MEMA_1 | 617.51 | 518.78 | 119.03 |
| MEMA_2 | 678.98 | 676.26 | 100.4 |
| MEMA_3 | 700.11 | 661.77 | 105.79 |
| MEMA_4 | 613.20000000000005 | 392.79 | 156.11000000000001 |
| MEMA_5 | 770.75 | 661.77 | 116.47 |
| MEMA_6 | 637.92999999999995 | 455.78 | 139.97 |
| MEMA_7 | 681.72 | 598.78 | 113.85 |
| MEMA_8 | 613.66999999999996 | 424.29 | 144.63 |
| MEMA_9 | 672.75 | 567.29 | 118.59 |
| MEMA_10 | 785.9 | 535.79 | 146.68 |
| MEMA_11 | 612.57000000000005 | 455.79 | 134.4 |
| MEMA_12 | 778.14 | 567.29 | 137.16999999999999 |
| MEMA_13 | 655.29 | 613.26 | 106.85 |
| MEMA_14 | 605.54999999999995 | 424.29 | 142.72 |
| MEMBA_0 | 763.16 | 661.77 | 115.32 |
| MEMBA_1 | 614.22 | 424.29 | 144.76 |
| MEMBA_2 | 786.19 | 598.77 | 131.30000000000001 |
| MEMCASN | 597.70000000000005 | 567.28 | 105.36 |
| MEMCKE | 664.85 | 409.81 | 162.22999999999999 |
| MEMCK_N | 589.49 | 441.31 | 133.58000000000001 |
| MEMCK_P | 589.74 | 441.3 | 133.63999999999999 |
| MEMCSN | 672.51 | 598.78 | 112.31 |
| MEMDM_0 | 794.11 | 598.79 | 132.62 |
| MEMDM_1 | 820.19 | 724.76 | 113.17 |
| MEMDQS_N0 | 672.98 | 598.78 | 112.39 |
| MEMDQS_N1 | 651.73 | 535.78 | 121.64 |
| MEMDQS_P0 | 670.88 | 598.78 | 112.04 |
| MEMDQS_P1 | 650.04 | 535.79 | 121.32 |
| MEMDQ_0 | 674.73 | 567.29 | 118.94 |
| MEMDQ_1 | 785.63 | 724.77 | 108.4 |
| MEMDQ_2 | 664.15 | 472.79 | 140.47 |
| MEMDQ_3 | 674.42 | 535.79 | 125.87 |
| MEMDQ_4 | 733.98 | 724.76 | 101.27 |
| MEMDQ_5 | 783.28 | 724.76 | 108.07 |
| MEMDQ_6 | 672.15 | 535.79 | 125.45 |
| MEMDQ_7 | 687.5 | 693.27 | 99.17 |
| MEMDQ_8 | 668.87 | 661.78 | 101.07 |
| MEMDQ_9 | 673.7 | 535.78 | 125.74 |
| MEMDQ_10 | 669.7 | 630.28 | 106.25 |
| MEMDQ_11 | 767.14 | 724.76 | 105.85 |
| MEMDQ_12 | 872.61 | 787.76 | 110.77 |
| MEMDQ_13 | 681.58 | 630.28 | 108.14 |
| MEMDQ_14 | 748.03 | 756.25 | 98.91 |
| MEMDQ_15 | 835.56 | 819.25 | 101.99 |
| MEMODT | 832.98 | 787.76 | 105.74 |
| MEMRASN | 651.39 | 693.26 | 93.96 |
| MEMWEN | 755.5 | 598.77 | 126.18 |
| MEZCN0_1 | 165.76 | 169.95 | 97.53 |
| MNG_RX_DN | 24993.759999999998 | 20186.7 | 123.81 |
| MNG_RX_DP | 25023.79 | 20281.82 | 123.38 |
| MNG_TX_DN | 25156.74 | 20433.060000000001 | 123.12 |
| MNG_TX_DP | 25169.01 | 20529.169999999998 | 122.6 |
| MPLLAV33 | 668.33 | 586.87 | 113.88 |
| MSATA_LED_N | 6168.63 | 5441.32 | 113.37 |
| MSATA_SSD_PRSNT_N | 6190.09 | 4952.99 | 124.98 |
| M_AB_CPU_VREF | 6007.09 | 4109.8599999999997 | 146.16 |
| M_AB_RESET_N | 2702.5 | 2910.3 | 92.86 |
| M_AB_VREF | 1767.7 | 1659.37 | 106.53 |
| M_A_ACT_N | 2935.96 | 3071.14 | 95.6 |
| M_A_ALERT_N | 2827.32 | 2974.6 | 95.05 |
| M_A_BA_0 | 2928.15 | 2672.6 | 109.56 |
| M_A_BA_1 | 2935.89 | 2521.2399999999998 | 116.45 |
| M_A_BG_0 | 2943.22 | 3115.37 | 94.47 |
| M_A_BG_1 | 2927.04 | 2925.76 | 100.04 |
| M_A_CKE_0 | 2903.53 | 3192.77 | 90.94 |
| M_A_CKE_1 | 2908.56 | 3219.61 | 90.34 |
| M_A_CKE_2 | 2677.54 | 2846.98 | 94.05 |
| M_A_CKE_3 | 2677.32 | 2888.52 | 92.69 |
| M_A_CLK_DN_0 | 2912.07 | 2972.59 | 97.96 |
| M_A_CLK_DN_1 | 2680.63 | 2477.4 | 108.2 |
| M_A_CLK_DN_2 | 2912.2 | 2768.28 | 105.2 |
| M_A_CLK_DN_3 | 2680.35 | 2382.4899999999998 | 112.5 |
| M_A_CLK_DP_0 | 2913.32 | 2983.07 | 97.66 |
| M_A_CLK_DP_1 | 2680.1 | 2487.88 | 107.73 |
| M_A_CLK_DP_2 | 2913.48 | 2778.76 | 104.85 |
| M_A_CLK_DP_3 | 2680.1 | 2392.9699999999998 | 112 |
| M_A_CS_N_0 | 2913.64 | 2815.31 | 103.49 |
| M_A_CS_N_1 | 2913.28 | 2965.62 | 98.23 |
| M_A_CS_N_2 | 2918.16 | 3000.68 | 97.25 |
| M_A_CS_N_3 | 2909.39 | 2945.77 | 98.77 |
| M_A_CS_N_4 | 2683.84 | 2324.2199999999998 | 115.47 |
| M_A_CS_N_5 | 2683.67 | 2525.13 | 106.28 |
| M_A_CS_N_6 | 2606.17 | 2589.59 | 100.64 |
| M_A_CS_N_7 | 2620.66 | 2519.98 | 104 |
| M_A_C_2 | 2932.5 | 2758.84 | 106.29 |
| M_A_DQS_DN_0 | 4434.41 | 4621.62 | 95.95 |
| M_A_DQS_DN_1 | 4312.5600000000004 | 4470 | 96.48 |
| M_A_DQS_DN_2 | 3831.99 | 3878.9 | 98.79 |
| M_A_DQS_DN_3 | 3541.31 | 3603.18 | 98.28 |
| M_A_DQS_DN_4 | 3011.46 | 2763.53 | 108.97 |
| M_A_DQS_DN_5 | 3222.97 | 3314.63 | 97.23 |
| M_A_DQS_DN_6 | 3299.15 | 3396.85 | 97.12 |
| M_A_DQS_DN_7 | 3453.65 | 3707.95 | 93.14 |
| M_A_DQS_DN_8 | 3159.62 | 2927.98 | 107.91 |
| M_A_DQS_DN_9 | 4433.8599999999997 | 4855.33 | 91.32 |
| M_A_DQS_DN_10 | 4305.6000000000004 | 4743.71 | 90.76 |
| M_A_DQS_DN_11 | 3839.3 | 3904.41 | 98.33 |
| M_A_DQS_DN_12 | 3538.67 | 3847.49 | 91.97 |
| M_A_DQS_DN_13 | 3008.28 | 3007.84 | 100.01 |
| M_A_DQS_DN_14 | 3220.42 | 3558.94 | 90.49 |
| M_A_DQS_DN_15 | 3293.56 | 3601.16 | 91.46 |
| M_A_DQS_DN_16 | 3450.14 | 3912.26 | 88.19 |
| M_A_DQS_DN_17 | 3160.05 | 2982.89 | 105.94 |
| M_A_DQS_DP_0 | 4432.84 | 4611.1400000000003 | 96.13 |
| M_A_DQS_DP_1 | 4311.76 | 4428.24 | 97.37 |
| M_A_DQS_DP_2 | 3831.53 | 3853.72 | 99.42 |
| M_A_DQS_DP_3 | 3540.02 | 3521.42 | 100.53 |
| M_A_DQS_DP_4 | 3011.72 | 2899.99 | 103.85 |
| M_A_DQS_DP_5 | 3221.47 | 3325.11 | 96.88 |
| M_A_DQS_DP_6 | 3296.91 | 3533.31 | 93.31 |
| M_A_DQS_DP_7 | 3454.3 | 3718.43 | 92.9 |
| M_A_DQS_DP_8 | 3160.88 | 2917.5 | 108.34 |
| M_A_DQS_DP_9 | 4433.8900000000003 | 4937.08 | 89.81 |
| M_A_DQS_DP_10 | 4306.5200000000004 | 4699.4799999999996 | 91.64 |
| M_A_DQS_DP_11 | 3838.73 | 4055.56 | 94.65 |
| M_A_DQS_DP_12 | 3540.16 | 3763.26 | 94.07 |
| M_A_DQS_DP_13 | 3007.96 | 2997.37 | 100.35 |
| M_A_DQS_DP_14 | 3218.32 | 3422.49 | 94.03 |
| M_A_DQS_DP_15 | 3292.21 | 3590.69 | 91.69 |
| M_A_DQS_DP_16 | 3449.34 | 3775.81 | 91.35 |
| M_A_DQS_DP_17 | 3161.7 | 3119.34 | 101.36 |
| M_A_DQ_0 | 4432.58 | 4989.3100000000004 | 88.84 |
| M_A_DQ_1 | 4434.0200000000004 | 4728.55 | 93.77 |
| M_A_DQ_2 | 4433.12 | 4681.47 | 94.7 |
| M_A_DQ_3 | 4436.1899999999996 | 4506.68 | 98.44 |
| M_A_DQ_4 | 4434.92 | 5110.9399999999996 | 86.77 |
| M_A_DQ_5 | 4430.5600000000004 | 4879.57 | 90.8 |
| M_A_DQ_6 | 4432.71 | 4679 | 94.74 |
| M_A_DQ_7 | 4438.76 | 4504.21 | 98.55 |
| M_A_DQ_8 | 4307.87 | 4751.71 | 90.66 |
| M_A_DQ_9 | 4309.84 | 4576.93 | 94.16 |
| M_A_DQ_10 | 4307.3100000000004 | 4555.1499999999996 | 94.56 |
| M_A_DQ_11 | 4309.08 | 4323.78 | 99.66 |
| M_A_DQ_12 | 4308.16 | 4888.04 | 88.14 |
| M_A_DQ_13 | 4308.75 | 4782.6499999999996 | 90.09 |
| M_A_DQ_14 | 4310.12 | 4512.68 | 95.51 |
| M_A_DQ_15 | 4307.01 | 4321.3100000000004 | 99.67 |
| M_A_DQ_16 | 3835 | 4162.49 | 92.13 |
| M_A_DQ_17 | 3835.49 | 3861.73 | 99.32 |
| M_A_DQ_18 | 3835.47 | 3799.95 | 100.93 |
| M_A_DQ_19 | 3841.68 | 3734.56 | 102.87 |
| M_A_DQ_20 | 3839.41 | 4284.12 | 89.62 |
| M_A_DQ_21 | 3836.32 | 4052.75 | 94.66 |
| M_A_DQ_22 | 3833.7 | 3797.48 | 100.95 |
| M_A_DQ_23 | 3832.37 | 3732.09 | 102.69 |
| M_A_DQ_24 | 3537.46 | 3870.19 | 91.4 |
| M_A_DQ_25 | 3537.44 | 3779.5 | 93.6 |
| M_A_DQ_26 | 3542.85 | 3593.63 | 98.59 |
| M_A_DQ_27 | 3541.69 | 3427.56 | 103.33 |
| M_A_DQ_28 | 3537.86 | 3977.12 | 88.96 |
| M_A_DQ_29 | 3540.86 | 3871.73 | 91.45 |
| M_A_DQ_30 | 3536.48 | 3591.16 | 98.48 |
| M_A_DQ_31 | 3541.87 | 3399.79 | 104.18 |
| M_A_DQ_32 | 3008.78 | 2985.14 | 100.79 |
| M_A_DQ_33 | 3011.83 | 2846 | 105.83 |
| M_A_DQ_34 | 3009.36 | 3017.6 | 99.73 |
| M_A_DQ_35 | 3011.18 | 3004.44 | 100.22 |
| M_A_DQ_36 | 3011.45 | 2932.91 | 102.68 |
| M_A_DQ_37 | 3011.05 | 2793.77 | 107.78 |
| M_A_DQ_38 | 3011.19 | 2965.37 | 101.55 |
| M_A_DQ_39 | 3008.62 | 2952.21 | 101.91 |
| M_A_DQ_40 | 3219.5 | 3410.26 | 94.41 |
| M_A_DQ_41 | 3222.15 | 3397.1 | 94.85 |
| M_A_DQ_42 | 3224.04 | 3568.7 | 90.34 |
| M_A_DQ_43 | 3222.3 | 3429.56 | 93.96 |
| M_A_DQ_44 | 3221.32 | 3358.03 | 95.93 |
| M_A_DQ_45 | 3221.57 | 3344.87 | 96.31 |
| M_A_DQ_46 | 3221.08 | 3516.47 | 91.6 |
| M_A_DQ_47 | 3215.87 | 3377.34 | 95.22 |
| M_A_DQ_48 | 3292.4 | 3578.46 | 92.01 |
| M_A_DQ_49 | 3290.9 | 3439.32 | 95.68 |
| M_A_DQ_50 | 3289 | 3610.92 | 91.08 |
| M_A_DQ_51 | 3294.31 | 3597.76 | 91.57 |
| M_A_DQ_52 | 3292.56 | 3526.23 | 93.37 |
| M_A_DQ_53 | 3291.77 | 3387.09 | 97.19 |
| M_A_DQ_54 | 3291.44 | 3558.69 | 92.49 |
| M_A_DQ_55 | 3293.03 | 3545.54 | 92.88 |
| M_A_DQ_56 | 3449.15 | 3763.58 | 91.65 |
| M_A_DQ_57 | 3448.66 | 3750.42 | 91.95 |
| M_A_DQ_58 | 3452.5 | 3922.02 | 88.03 |
| M_A_DQ_59 | 3449.62 | 3782.88 | 91.19 |
| M_A_DQ_60 | 3448.8 | 3711.35 | 92.93 |
| M_A_DQ_61 | 3448.27 | 3698.19 | 93.24 |
| M_A_DQ_62 | 3450.56 | 3869.79 | 89.17 |
| M_A_DQ_63 | 3448.77 | 3730.66 | 92.44 |
| M_A_ECC_0 | 3165.98 | 3171.57 | 99.82 |
| M_A_ECC_1 | 3161.86 | 2885.5 | 109.58 |
| M_A_ECC_2 | 3159.83 | 2918.43 | 108.27 |
| M_A_ECC_3 | 3159.27 | 2838.34 | 111.31 |
| M_A_ECC_4 | 3168.24 | 3278.5 | 96.64 |
| M_A_ECC_5 | 3159.08 | 3087.13 | 102.33 |
| M_A_ECC_6 | 3162.52 | 3050.66 | 103.67 |
| M_A_ECC_7 | 3160.35 | 2945.27 | 107.3 |
| M_A_MA_0 | 2921.03 | 2510.98 | 116.33 |
| M_A_MA_1 | 2935.45 | 2809.99 | 104.46 |
| M_A_MA_2 | 2928.81 | 2675.08 | 109.48 |
| M_A_MA_3 | 2930.94 | 2946.45 | 99.47 |
| M_A_MA_4 | 2926.64 | 2712.61 | 107.89 |
| M_A_MA_5 | 2916.63 | 2834.37 | 102.9 |
| M_A_MA_6 | 2932.46 | 2943.98 | 99.61 |
| M_A_MA_7 | 2931.68 | 2926.6 | 100.17 |
| M_A_MA_8 | 2931.76 | 2994.45 | 97.91 |
| M_A_MA_9 | 2932.92 | 3006.68 | 97.55 |
| M_A_MA_10 | 2936.62 | 2358.89 | 124.49 |
| M_A_MA_11 | 2932.83 | 2777.07 | 105.61 |
| M_A_MA_12 | 2935.06 | 2968.44 | 98.88 |
| M_A_MA_13 | 2925.3 | 2744.86 | 106.57 |
| M_A_MA_14 | 2933.68 | 2600.4 | 112.82 |
| M_A_MA_15 | 2927.48 | 2638.14 | 110.97 |
| M_A_MA_16 | 2939.39 | 2573.6799999999998 | 114.21 |
| M_A_MA_17 | 2943.33 | 2797.09 | 105.23 |
| M_A_ODT_0 | 2919.92 | 2938.69 | 99.36 |
| M_A_ODT_1 | 2925.84 | 2828.45 | 103.44 |
| M_A_ODT_2 | 2667.54 | 2472.9 | 107.87 |
| M_A_ODT_3 | 2680.4 | 2726.76 | 98.3 |
| M_A_PAR | 2929.99 | 2414.31 | 121.36 |
| M_B_ACT_N | 1936.36 | 2208.96 | 87.66 |
| M_B_ALERT_N | 1788.47 | 1977.72 | 90.43 |
| M_B_BA_0 | 1938.59 | 1701.02 | 113.97 |
| M_B_BA_1 | 1938.73 | 1509.66 | 128.41999999999999 |
| M_B_BG_0 | 1951.08 | 2198.4899999999998 | 88.75 |
| M_B_BG_1 | 1942.02 | 2128.88 | 91.22 |
| M_B_CKE_0 | 1867.12 | 2210.59 | 84.46 |
| M_B_CKE_1 | 1875.22 | 2117.4299999999998 | 88.56 |
| M_B_CKE_2 | 1405.17 | 1744.8 | 80.53 |
| M_B_CKE_3 | 1376.21 | 1651.64 | 83.32 |
| M_B_CLK_DN_0 | 1880.22 | 1870.41 | 100.52 |
| M_B_CLK_DN_1 | 1386.11 | 1375.22 | 100.79 |
| M_B_CLK_DN_2 | 1883.59 | 1666.1 | 113.05 |
| M_B_CLK_DN_3 | 1385.09 | 1280.31 | 108.18 |
| M_B_CLK_DP_0 | 1880.36 | 1800.89 | 104.41 |
| M_B_CLK_DP_1 | 1386.62 | 1305.7 | 106.2 |
| M_B_CLK_DP_2 | 1883.68 | 1596.58 | 117.98 |
| M_B_CLK_DP_3 | 1384.8 | 1210.79 | 114.37 |
| M_B_CS_N_0 | 1889.58 | 1633.13 | 115.7 |
| M_B_CS_N_1 | 1882.63 | 1848.74 | 101.83 |
| M_B_CS_N_2 | 1974.21 | 2058.5 | 95.91 |
| M_B_CS_N_3 | 1962.43 | 1948.89 | 100.7 |
| M_B_CS_N_4 | 1393.55 | 1327.34 | 104.99 |
| M_B_CS_N_5 | 1389.18 | 1462.95 | 94.96 |
| M_B_CS_N_6 | 1481 | 1607.41 | 92.14 |
| M_B_CS_N_7 | 1475.29 | 1497.8 | 98.5 |
| M_B_C_2 | 1946.67 | 1896.66 | 102.64 |
| M_B_DQS_DN_0 | 3470.38 | 3755.34 | 92.41 |
| M_B_DQS_DN_1 | 3040.56 | 3374.32 | 90.11 |
| M_B_DQS_DN_2 | 2656.71 | 2673.82 | 99.36 |
| M_B_DQS_DN_3 | 2165.3000000000002 | 2442.1999999999998 | 88.66 |
| M_B_DQS_DN_4 | 1980.51 | 1901.35 | 104.16 |
| M_B_DQS_DN_5 | 2202.9899999999998 | 2183.0500000000002 | 100.91 |
| M_B_DQS_DN_6 | 2221.54 | 2414.67 | 92 |
| M_B_DQS_DN_7 | 2504.7399999999998 | 2765.77 | 90.56 |
| M_B_DQS_DN_8 | 2435.91 | 2189.9 | 111.23 |
| M_B_DQS_DN_9 | 3473.66 | 3835.55 | 90.56 |
| M_B_DQS_DN_10 | 3038.2 | 3439.83 | 88.32 |
| M_B_DQS_DN_11 | 2655.65 | 2808.73 | 94.55 |
| M_B_DQS_DN_12 | 2164.6999999999998 | 2537.11 | 85.32 |
| M_B_DQS_DN_13 | 1981.3 | 2145.66 | 92.34 |
| M_B_DQS_DN_14 | 2202.13 | 2372.66 | 92.81 |
| M_B_DQS_DN_15 | 2222.88 | 2618.98 | 84.88 |
| M_B_DQS_DN_16 | 2505.65 | 2835.38 | 88.37 |
| M_B_DQS_DN_17 | 2434.6999999999998 | 2394.21 | 101.69 |
| M_B_DQS_DP_0 | 3470.73 | 3799.56 | 91.35 |
| M_B_DQS_DP_1 | 3039.25 | 3223.16 | 94.29 |
| M_B_DQS_DP_2 | 2655.97 | 2743.34 | 96.82 |
| M_B_DQS_DP_3 | 2160.3000000000002 | 2400.44 | 90 |
| M_B_DQS_DP_4 | 1981.24 | 2037.81 | 97.22 |
| M_B_DQS_DP_5 | 2200.36 | 2113.5300000000002 | 104.11 |
| M_B_DQS_DP_6 | 2221.71 | 2551.13 | 87.09 |
| M_B_DQS_DP_7 | 2500.41 | 2681.55 | 93.24 |
| M_B_DQS_DP_8 | 2436.64 | 2234.12 | 109.06 |
| M_B_DQS_DP_9 | 3471.53 | 3986.7 | 87.08 |
| M_B_DQS_DP_10 | 3039.47 | 3425 | 88.74 |
| M_B_DQS_DP_11 | 2656.03 | 2865.18 | 92.7 |
| M_B_DQS_DP_12 | 2164.3000000000002 | 2492.88 | 86.82 |
| M_B_DQS_DP_13 | 1981.2 | 2135.19 | 92.79 |
| M_B_DQS_DP_14 | 2201.88 | 2290.91 | 96.11 |
| M_B_DQS_DP_15 | 2220.38 | 2608.5100000000002 | 85.12 |
| M_B_DQS_DP_16 | 2503.77 | 2793.63 | 89.62 |
| M_B_DQS_DP_17 | 2435.38 | 2475.96 | 98.36 |
| M_B_DQ_0 | 3470.39 | 4123.03 | 84.17 |
| M_B_DQ_1 | 3469.73 | 3792.87 | 91.48 |
| M_B_DQ_2 | 3474.11 | 3731.09 | 93.11 |
| M_B_DQ_3 | 3473.52 | 3625.7 | 95.8 |
| M_B_DQ_4 | 3472.36 | 4229.96 | 82.09 |
| M_B_DQ_5 | 3469.79 | 3914.49 | 88.64 |
| M_B_DQ_6 | 3475.97 | 3728.62 | 93.22 |
| M_B_DQ_7 | 3467.01 | 3663.23 | 94.64 |
| M_B_DQ_8 | 3034.54 | 3517.23 | 86.28 |
| M_B_DQ_9 | 3037.63 | 3411.85 | 89.03 |
| M_B_DQ_10 | 3036.66 | 3295.37 | 92.15 |
| M_B_DQ_11 | 3038.73 | 2994.6 | 101.47 |
| M_B_DQ_12 | 3035.95 | 3653.56 | 83.1 |
| M_B_DQ_13 | 3039.18 | 3548.17 | 85.65 |
| M_B_DQ_14 | 3036.46 | 3417 | 88.86 |
| M_B_DQ_15 | 3032.47 | 3046.83 | 99.53 |
| M_B_DQ_16 | 2657.99 | 3012.11 | 88.24 |
| M_B_DQ_17 | 2655.08 | 2671.35 | 99.39 |
| M_B_DQ_18 | 2652.4 | 2798.97 | 94.76 |
| M_B_DQ_19 | 2651.87 | 2718.88 | 97.54 |
| M_B_DQ_20 | 2651.84 | 3009.64 | 88.11 |
| M_B_DQ_21 | 2651.79 | 2818.27 | 94.09 |
| M_B_DQ_22 | 2653.64 | 2811.2 | 94.4 |
| M_B_DQ_23 | 2652.44 | 2731.11 | 97.12 |
| M_B_DQ_24 | 2163.1999999999998 | 2599.81 | 83.21 |
| M_B_DQ_25 | 2164.67 | 2494.42 | 86.78 |
| M_B_DQ_26 | 2165.83 | 2487.35 | 87.07 |
| M_B_DQ_27 | 2166.13 | 2281.2800000000002 | 94.95 |
| M_B_DQ_28 | 2169.13 | 2597.34 | 83.51 |
| M_B_DQ_29 | 2162.27 | 2531.9499999999998 | 85.4 |
| M_B_DQ_30 | 2164.14 | 2484.88 | 87.09 |
| M_B_DQ_31 | 2166.2600000000002 | 2253.5100000000002 | 96.13 |
| M_B_DQ_32 | 1983.25 | 2122.96 | 93.42 |
| M_B_DQ_33 | 1980.75 | 1983.82 | 99.85 |
| M_B_DQ_34 | 1981.12 | 2155.42 | 91.91 |
| M_B_DQ_35 | 1983.25 | 2142.2600000000002 | 92.58 |
| M_B_DQ_36 | 1982.59 | 2070.73 | 95.74 |
| M_B_DQ_37 | 1982.73 | 1931.59 | 102.65 |
| M_B_DQ_38 | 1980 | 2103.19 | 94.14 |
| M_B_DQ_39 | 1979.07 | 2090.0300000000002 | 94.69 |
| M_B_DQ_40 | 2180.54 | 2293.38 | 95.08 |
| M_B_DQ_41 | 2176.4 | 2185.52 | 99.58 |
| M_B_DQ_42 | 2178.73 | 2411.8200000000002 | 90.34 |
| M_B_DQ_43 | 2178.63 | 2137.98 | 101.9 |
| M_B_DQ_44 | 2176.6 | 2241.15 | 97.12 |
| M_B_DQ_45 | 2178.52 | 2227.9899999999998 | 97.78 |
| M_B_DQ_46 | 2173.14 | 2384.89 | 91.12 |
| M_B_DQ_47 | 2174.0300000000002 | 2125.7600000000002 | 102.27 |
| M_B_DQ_48 | 2223.38 | 2596.2800000000002 | 85.64 |
| M_B_DQ_49 | 2219.0700000000002 | 2457.14 | 90.31 |
| M_B_DQ_50 | 2220.1 | 2628.74 | 84.45 |
| M_B_DQ_51 | 2222.34 | 2615.58 | 84.97 |
| M_B_DQ_52 | 2220.2199999999998 | 2544.0500000000002 | 87.27 |
| M_B_DQ_53 | 2220.6999999999998 | 2404.91 | 92.34 |
| M_B_DQ_54 | 2222.33 | 2576.5100000000002 | 86.25 |
| M_B_DQ_55 | 2215.1999999999998 | 2563.36 | 86.42 |
| M_B_DQ_56 | 2512.31 | 2712 | 92.64 |
| M_B_DQ_57 | 2508.64 | 2633.54 | 95.26 |
| M_B_DQ_58 | 2518.06 | 2939.84 | 85.65 |
| M_B_DQ_59 | 2510.54 | 2800.7 | 89.64 |
| M_B_DQ_60 | 2515.04 | 2714.47 | 92.65 |
| M_B_DQ_61 | 2516.8200000000002 | 2646.61 | 95.1 |
| M_B_DQ_62 | 2511 | 2847.61 | 88.18 |
| M_B_DQ_63 | 2509.9699999999998 | 2653.78 | 94.58 |
| M_B_ECC_0 | 2438.0500000000002 | 2582.89 | 94.39 |
| M_B_ECC_1 | 2440.2800000000002 | 2351.52 | 103.77 |
| M_B_ECC_2 | 2433.85 | 2180.35 | 111.63 |
| M_B_ECC_3 | 2437.9699999999998 | 2020.26 | 120.68 |
| M_B_ECC_4 | 2439.2800000000002 | 2689.82 | 90.69 |
| M_B_ECC_5 | 2439.5700000000002 | 2458.4499999999998 | 99.23 |
| M_B_ECC_6 | 2437.27 | 2232.58 | 109.17 |
| M_B_ECC_7 | 2433.33 | 2072.4899999999998 | 117.41 |
| M_B_MA_0 | 1938.88 | 1648.8 | 117.59 |
| M_B_MA_1 | 1936.01 | 1947.81 | 99.39 |
| M_B_MA_2 | 1938.25 | 1823.5 | 106.29 |
| M_B_MA_3 | 1933.67 | 2084.27 | 92.77 |
| M_B_MA_4 | 1945.09 | 1915.73 | 101.53 |
| M_B_MA_5 | 1935.48 | 1946.89 | 99.41 |
| M_B_MA_6 | 1933.1 | 2081.8000000000002 | 92.86 |
| M_B_MA_7 | 1934.5 | 2024.42 | 95.56 |
| M_B_MA_8 | 1934.73 | 2012.27 | 96.15 |
| M_B_MA_9 | 1939.66 | 2064.5 | 93.95 |
| M_B_MA_10 | 1938.53 | 1631.41 | 118.83 |
| M_B_MA_11 | 1938.77 | 1954.89 | 99.18 |
| M_B_MA_12 | 1948.03 | 2146.2600000000002 | 90.76 |
| M_B_MA_13 | 1946.02 | 1653.28 | 117.71 |
| M_B_MA_14 | 1947.96 | 1708.82 | 113.99 |
| M_B_MA_15 | 1943.12 | 1790.66 | 108.51 |
| M_B_MA_16 | 1937.31 | 1616.8 | 119.82 |
| M_B_MA_17 | 1949.22 | 1814.91 | 107.4 |
| M_B_ODT_0 | 1876.45 | 1836.51 | 102.17 |
| M_B_ODT_1 | 1863.35 | 1846.27 | 100.93 |
| M_B_ODT_2 | 1389.8 | 1450.72 | 95.8 |
| M_B_ODT_3 | 1391.9 | 1515.18 | 91.86 |
| M_B_PAR | 1938.3 | 1552.13 | 124.88 |
| M_CD_CPU_VREF | 2576.44 | 2785.68 | 92.49 |
| M_CD_RESET_N | 2516.83 | 2445.79 | 102.9 |
| M_CD_VREF | 1523.65 | 1595.47 | 95.5 |
| M_C_ACT_N | 2974.83 | 2821.33 | 105.44 |
| M_C_ALERT_N | 2526.11 | 2350.09 | 107.49 |
| M_C_BA_0 | 2977.76 | 2937.75 | 101.36 |
| M_C_BA_1 | 2979.82 | 2895.79 | 102.9 |
| M_C_BG_0 | 2981.84 | 2770.86 | 107.61 |
| M_C_BG_1 | 2980.52 | 2715.95 | 109.74 |
| M_C_CKE_0 | 2982.05 | 2688.26 | 110.93 |
| M_C_CKE_1 | 2983.33 | 2675.1 | 111.52 |
| M_C_CKE_2 | 2985.22 | 2302.4699999999998 | 129.65 |
| M_C_CKE_3 | 2989.72 | 2329.31 | 128.35 |
| M_C_CLK_DN_0 | 2990.18 | 2780.28 | 107.55 |
| M_C_CLK_DN_1 | 2990.31 | 2533.29 | 118.04 |
| M_C_CLK_DN_2 | 2992.02 | 2685.37 | 111.42 |
| M_C_CLK_DN_3 | 2991.89 | 2328.98 | 128.46 |
| M_C_CLK_DP_0 | 2990 | 2723.82 | 109.77 |
| M_C_CLK_DP_1 | 2991.07 | 2476.83 | 120.76 |
| M_C_CLK_DP_2 | 2991.71 | 2628.91 | 113.8 |
| M_C_CLK_DP_3 | 2991.61 | 2272.52 | 131.63999999999999 |
| M_C_CS_N_0 | 2991.19 | 3244.56 | 92.19 |
| M_C_CS_N_1 | 2992.18 | 3354.87 | 89.19 |
| M_C_CS_N_2 | 3004.88 | 3444.63 | 87.23 |
| M_C_CS_N_3 | 2990.42 | 3335.02 | 89.67 |
| M_C_CS_N_4 | 2988.44 | 2713.47 | 110.13 |
| M_C_CS_N_5 | 2984.46 | 2969.08 | 100.52 |
| M_C_CS_N_6 | 2987.35 | 3153.54 | 94.73 |
| M_C_CS_N_7 | 2984.88 | 3128.03 | 95.42 |
| M_C_C_2 | 2974.89 | 3188.09 | 93.31 |
| M_C_DQS_DN_0 | 3956.8 | 3803.61 | 104.03 |
| M_C_DQS_DN_1 | 3264.55 | 3651.99 | 89.39 |
| M_C_DQS_DN_2 | 3433.62 | 3340.89 | 102.78 |
| M_C_DQS_DN_3 | 3090.79 | 3178.67 | 97.24 |
| M_C_DQS_DN_4 | 3206.76 | 3192.78 | 100.44 |
| M_C_DQS_DN_5 | 3671.84 | 3813.28 | 96.29 |
| M_C_DQS_DN_6 | 4084.34 | 4453.1099999999997 | 91.72 |
| M_C_DQS_DN_7 | 4327.21 | 4690.71 | 92.25 |
| M_C_DQS_DN_8 | 3146.21 | 2867.57 | 109.72 |
| M_C_DQS_DN_9 | 3968.36 | 4033.22 | 98.39 |
| M_C_DQS_DN_10 | 3269.81 | 3706.9 | 88.21 |
| M_C_DQS_DN_11 | 3433.61 | 3395.8 | 101.11 |
| M_C_DQS_DN_12 | 3091.79 | 3233.58 | 95.62 |
| M_C_DQS_DN_13 | 3206.57 | 3247.69 | 98.73 |
| M_C_DQS_DN_14 | 3672.29 | 3908.19 | 93.96 |
| M_C_DQS_DN_15 | 4083.1 | 4672.12 | 87.39 |
| M_C_DQS_DN_16 | 4327.17 | 4895.0200000000004 | 88.4 |
| M_C_DQS_DN_17 | 3144.46 | 2922.48 | 107.6 |
| M_C_DQS_DP_0 | 3953.39 | 3778.43 | 104.63 |
| M_C_DQS_DP_1 | 3264.84 | 3570.23 | 91.45 |
| M_C_DQS_DP_2 | 3433.73 | 3330.41 | 103.1 |
| M_C_DQS_DP_3 | 3090.85 | 3042.21 | 101.6 |
| M_C_DQS_DP_4 | 3204.86 | 3234.54 | 99.08 |
| M_C_DQS_DP_5 | 3670.92 | 3823.76 | 96 |
| M_C_DQS_DP_6 | 4083.37 | 4494.87 | 90.85 |
| M_C_DQS_DP_7 | 4327.32 | 4646.49 | 93.13 |
| M_C_DQS_DP_8 | 3144.65 | 2857.09 | 110.06 |
| M_C_DQS_DP_9 | 3966 | 4074.97 | 97.33 |
| M_C_DQS_DP_10 | 3270.35 | 3662.67 | 89.29 |
| M_C_DQS_DP_11 | 3434.69 | 3532.25 | 97.24 |
| M_C_DQS_DP_12 | 3090.39 | 3244.05 | 95.26 |
| M_C_DQS_DP_13 | 3203.97 | 3331.92 | 96.16 |
| M_C_DQS_DP_14 | 3671.47 | 3757.04 | 97.72 |
| M_C_DQS_DP_15 | 4082.57 | 4716.3500000000004 | 86.56 |
| M_C_DQS_DP_16 | 4327.91 | 4813.2700000000004 | 89.92 |
| M_C_DQS_DP_17 | 3147.49 | 3058.93 | 102.9 |
| M_C_DQ_0 | 3975.71 | 4181.8999999999996 | 95.07 |
| M_C_DQ_1 | 3972.72 | 3910.54 | 101.59 |
| M_C_DQ_2 | 3980.83 | 3739.36 | 106.46 |
| M_C_DQ_3 | 3981.78 | 3684.57 | 108.07 |
| M_C_DQ_4 | 3981.41 | 4303.53 | 92.51 |
| M_C_DQ_5 | 3979.32 | 3948.06 | 100.79 |
| M_C_DQ_6 | 3978.88 | 3791.59 | 104.94 |
| M_C_DQ_7 | 3982.38 | 3726.2 | 106.88 |
| M_C_DQ_8 | 3266.96 | 3769.6 | 86.67 |
| M_C_DQ_9 | 3262.83 | 3664.22 | 89.05 |
| M_C_DQ_10 | 3264.18 | 3737.14 | 87.34 |
| M_C_DQ_11 | 3267.7 | 3451.07 | 94.69 |
| M_C_DQ_12 | 3264.63 | 3781.83 | 86.32 |
| M_C_DQ_13 | 3263.56 | 3621.74 | 90.11 |
| M_C_DQ_14 | 3265.43 | 3694.67 | 88.38 |
| M_C_DQ_15 | 3267.93 | 3543.3 | 92.23 |
| M_C_DQ_16 | 3471.6 | 3584.48 | 96.85 |
| M_C_DQ_17 | 3471.47 | 3298.42 | 105.25 |
| M_C_DQ_18 | 3469.2 | 3426.04 | 101.26 |
| M_C_DQ_19 | 3475.38 | 3265.95 | 106.41 |
| M_C_DQ_20 | 3467.5 | 3596.71 | 96.41 |
| M_C_DQ_21 | 3466.14 | 3310.64 | 104.7 |
| M_C_DQ_22 | 3467.43 | 3478.27 | 99.69 |
| M_C_DQ_23 | 3467.18 | 3318.18 | 104.49 |
| M_C_DQ_24 | 3093.03 | 3256.28 | 94.99 |
| M_C_DQ_25 | 3088.36 | 3096.19 | 99.75 |
| M_C_DQ_26 | 3091.44 | 3223.82 | 95.89 |
| M_C_DQ_27 | 3093.05 | 2937.75 | 105.29 |
| M_C_DQ_28 | 3093.87 | 3308.51 | 93.51 |
| M_C_DQ_29 | 3090.93 | 3148.42 | 98.17 |
| M_C_DQ_30 | 3093.39 | 3276.05 | 94.42 |
| M_C_DQ_31 | 3091.14 | 2989.98 | 103.38 |
| M_C_DQ_32 | 3207.88 | 3319.69 | 96.63 |
| M_C_DQ_33 | 3208.02 | 3045.85 | 105.32 |
| M_C_DQ_34 | 3210.25 | 3461.55 | 92.74 |
| M_C_DQ_35 | 3209.78 | 3353.69 | 95.71 |
| M_C_DQ_36 | 3205.5 | 3172.76 | 101.03 |
| M_C_DQ_37 | 3205.93 | 3033.62 | 105.68 |
| M_C_DQ_38 | 3207.21 | 3259.92 | 98.38 |
| M_C_DQ_39 | 3206.77 | 3246.76 | 98.77 |
| M_C_DQ_40 | 3672.2 | 3704.81 | 99.12 |
| M_C_DQ_41 | 3675.46 | 3761.05 | 97.72 |
| M_C_DQ_42 | 3676.36 | 4151.45 | 88.56 |
| M_C_DQ_43 | 3671.89 | 3888.21 | 94.44 |
| M_C_DQ_44 | 3673.73 | 3652.58 | 100.58 |
| M_C_DQ_45 | 3672.17 | 3654.12 | 100.49 |
| M_C_DQ_46 | 3669.84 | 4015.12 | 91.4 |
| M_C_DQ_47 | 3670.19 | 3781.29 | 97.06 |
| M_C_DQ_48 | 4081.41 | 4365.3100000000004 | 93.5 |
| M_C_DQ_49 | 4080.08 | 4240.87 | 96.21 |
| M_C_DQ_50 | 4086.46 | 4721.88 | 86.54 |
| M_C_DQ_51 | 4086.66 | 4723.42 | 86.52 |
| M_C_DQ_52 | 4082.45 | 4477.18 | 91.18 |
| M_C_DQ_53 | 4080.07 | 4243.34 | 96.15 |
| M_C_DQ_54 | 4082.74 | 4724.3500000000004 | 86.42 |
| M_C_DQ_55 | 4085.69 | 4725.8999999999996 | 86.45 |
| M_C_DQ_56 | 4326.3599999999997 | 4641.03 | 93.22 |
| M_C_DQ_57 | 4325.84 | 4518.47 | 95.74 |
| M_C_DQ_58 | 4330.22 | 5083.58 | 85.18 |
| M_C_DQ_59 | 4327.8100000000004 | 4889.74 | 88.51 |
| M_C_DQ_60 | 4322.18 | 4464.7 | 96.81 |
| M_C_DQ_61 | 4326.46 | 4480.9399999999996 | 96.55 |
| M_C_DQ_62 | 4329.43 | 4947.25 | 87.51 |
| M_C_DQ_63 | 4327.88 | 4753.42 | 91.05 |
| M_C_ECC_0 | 3142.6 | 3071.16 | 102.33 |
| M_C_ECC_1 | 3145.5 | 2785.09 | 112.94 |
| M_C_ECC_2 | 3139.12 | 2912.72 | 107.77 |
| M_C_ECC_3 | 3141.3 | 2752.63 | 114.12 |
| M_C_ECC_4 | 3145.56 | 3123.39 | 100.71 |
| M_C_ECC_5 | 3141.91 | 2837.32 | 110.73 |
| M_C_ECC_6 | 3137.73 | 2964.95 | 105.83 |
| M_C_ECC_7 | 3142.29 | 2804.86 | 112.03 |
| M_C_MA_0 | 2977.86 | 2885.53 | 103.2 |
| M_C_MA_1 | 2978.52 | 2442.1999999999998 | 121.96 |
| M_C_MA_2 | 2980.56 | 2441.9899999999998 | 122.05 |
| M_C_MA_3 | 2998.97 | 2486.42 | 120.61 |
| M_C_MA_4 | 2979.32 | 2389.7600000000002 | 124.67 |
| M_C_MA_5 | 2977.13 | 2384.56 | 124.85 |
| M_C_MA_6 | 2978.12 | 2494.17 | 119.4 |
| M_C_MA_7 | 2983.61 | 2476.79 | 120.46 |
| M_C_MA_8 | 2978.21 | 2409.94 | 123.58 |
| M_C_MA_9 | 2990.83 | 2502.17 | 119.53 |
| M_C_MA_10 | 2976.75 | 3002.84 | 99.13 |
| M_C_MA_11 | 2976.38 | 2392.56 | 124.4 |
| M_C_MA_12 | 2976.02 | 2663.93 | 111.72 |
| M_C_MA_13 | 2978.12 | 2930.01 | 101.64 |
| M_C_MA_14 | 2979.82 | 2985.55 | 99.81 |
| M_C_MA_15 | 2977 | 3067.39 | 97.05 |
| M_C_MA_16 | 2979.97 | 2948.23 | 101.08 |
| M_C_MA_17 | 2980.35 | 3106.34 | 95.94 |
| M_C_ODT_0 | 2994.46 | 3367.94 | 88.91 |
| M_C_ODT_1 | 2989.03 | 3447.1 | 86.71 |
| M_C_ODT_2 | 2988.69 | 2862.15 | 104.42 |
| M_C_ODT_3 | 2990.2 | 3101.31 | 96.42 |
| M_C_PAR | 2979.06 | 2788.86 | 106.82 |
| M_D_ACT_N | 1878.67 | 1799.15 | 104.42 |
| M_D_ALERT_N | 1694.86 | 1567.91 | 108.1 |
| M_D_BA_0 | 1874.64 | 2060.87 | 90.96 |
| M_D_BA_1 | 1874.38 | 1909.51 | 98.16 |
| M_D_BG_0 | 1874.81 | 1788.68 | 104.82 |
| M_D_BG_1 | 1874.39 | 1599.07 | 117.22 |
| M_D_CKE_0 | 1920.49 | 1731.38 | 110.92 |
| M_D_CKE_1 | 1914.63 | 1692.92 | 113.1 |
| M_D_CKE_2 | 1916.52 | 1294.99 | 147.99 |
| M_D_CKE_3 | 1925.14 | 1267.1300000000001 | 151.93 |
| M_D_CLK_DN_0 | 1926.19 | 1718.1 | 112.11 |
| M_D_CLK_DN_1 | 1926.78 | 1471.11 | 130.97 |
| M_D_CLK_DN_2 | 1927.55 | 1623.19 | 118.75 |
| M_D_CLK_DN_3 | 1926.58 | 1266.8 | 152.08000000000001 |
| M_D_CLK_DP_0 | 1926.97 | 1581.64 | 121.83 |
| M_D_CLK_DP_1 | 1926.5 | 1334.65 | 144.34 |
| M_D_CLK_DP_2 | 1927.16 | 1486.73 | 129.62 |
| M_D_CLK_DP_3 | 1925.79 | 1130.3399999999999 | 170.37 |
| M_D_CS_N_0 | 1930.98 | 2102.38 | 91.85 |
| M_D_CS_N_1 | 1918.91 | 2317.9899999999998 | 82.78 |
| M_D_CS_N_2 | 1941.56 | 2338.35 | 83.03 |
| M_D_CS_N_3 | 1943.32 | 2228.7399999999998 | 87.19 |
| M_D_CS_N_4 | 1924.05 | 1676.59 | 114.76 |
| M_D_CS_N_5 | 1925.28 | 1972.2 | 97.62 |
| M_D_CS_N_6 | 1930.69 | 2021.96 | 95.49 |
| M_D_CS_N_7 | 1929.09 | 1752.35 | 110.09 |
| M_D_C_2 | 1872.54 | 2216.5100000000002 | 84.48 |
| M_D_DQS_DN_0 | 2593.62 | 2741.43 | 94.61 |
| M_D_DQS_DN_1 | 2407.77 | 2535.11 | 94.98 |
| M_D_DQS_DN_2 | 2227.14 | 2318.71 | 96.05 |
| M_D_DQS_DN_3 | 2039.31 | 2196.4899999999998 | 92.84 |
| M_D_DQS_DN_4 | 2159.42 | 2137.1 | 101.04 |
| M_D_DQS_DN_5 | 2389.7399999999998 | 2627 | 90.97 |
| M_D_DQS_DN_6 | 3067.38 | 3294.53 | 93.11 |
| M_D_DQS_DN_7 | 3312.64 | 3653.82 | 90.66 |
| M_D_DQS_DN_8 | 1950.98 | 1885.39 | 103.48 |
| M_D_DQS_DN_9 | 2592.85 | 2956.34 | 87.7 |
| M_D_DQS_DN_10 | 2399.66 | 2710.02 | 88.55 |
| M_D_DQS_DN_11 | 2226.11 | 2453.62 | 90.73 |
| M_D_DQS_DN_12 | 2040.06 | 2251.4 | 90.61 |
| M_D_DQS_DN_13 | 2161.06 | 2366.71 | 91.31 |
| M_D_DQS_DN_14 | 2398.61 | 2831.31 | 84.72 |
| M_D_DQS_DN_15 | 3069.9 | 3582.94 | 85.68 |
| M_D_DQS_DN_16 | 3311.83 | 3763.43 | 88 |
| M_D_DQS_DN_17 | 1953.37 | 1940.3 | 100.67 |
| M_D_DQS_DP_0 | 2592.29 | 2810.95 | 92.22 |
| M_D_DQS_DP_1 | 2405.38 | 2493.35 | 96.47 |
| M_D_DQS_DP_2 | 2227.98 | 2388.23 | 93.29 |
| M_D_DQS_DP_3 | 2036.61 | 2060.0300000000002 | 98.86 |
| M_D_DQS_DP_4 | 2158.4699999999998 | 2218.86 | 97.28 |
| M_D_DQS_DP_5 | 2388.11 | 2637.48 | 90.55 |
| M_D_DQS_DP_6 | 3067.49 | 3445.69 | 89.02 |
| M_D_DQS_DP_7 | 3312.77 | 3609.6 | 91.78 |
| M_D_DQS_DP_8 | 1954.63 | 1874.91 | 104.25 |
| M_D_DQS_DP_9 | 2593.66 | 3012.79 | 86.09 |
| M_D_DQS_DP_10 | 2397.7800000000002 | 2625.79 | 91.32 |
| M_D_DQS_DP_11 | 2226.23 | 2510.0700000000002 | 88.69 |
| M_D_DQS_DP_12 | 2036.64 | 2261.87 | 90.04 |
| M_D_DQS_DP_13 | 2158.4299999999998 | 2450.94 | 88.07 |
| M_D_DQS_DP_14 | 2397.41 | 2694.86 | 88.96 |
| M_D_DQS_DP_15 | 3069.36 | 3557.77 | 86.27 |
| M_D_DQS_DP_16 | 3309.39 | 3721.68 | 88.92 |
| M_D_DQS_DP_17 | 1952.91 | 2076.75 | 94.04 |
| M_D_DQ_0 | 2593.2800000000002 | 3039.72 | 85.31 |
| M_D_DQ_1 | 2593.75 | 2753.66 | 94.19 |
| M_D_DQ_2 | 2593.2800000000002 | 2917.18 | 88.9 |
| M_D_DQ_3 | 2594.54 | 2782.39 | 93.25 |
| M_D_DQ_4 | 2593.86 | 3051.95 | 84.99 |
| M_D_DQ_5 | 2592.46 | 2925.88 | 88.6 |
| M_D_DQ_6 | 2600.77 | 2904.11 | 89.55 |
| M_D_DQ_7 | 2596.34 | 2809.32 | 92.42 |
| M_D_DQ_8 | 2406.7399999999998 | 2652.72 | 90.73 |
| M_D_DQ_9 | 2410.88 | 2587.34 | 93.18 |
| M_D_DQ_10 | 2410.85 | 2740.26 | 87.98 |
| M_D_DQ_11 | 2407.58 | 2454.19 | 98.1 |
| M_D_DQ_12 | 2414.14 | 2854.35 | 84.58 |
| M_D_DQ_13 | 2409.44 | 2679.56 | 89.92 |
| M_D_DQ_14 | 2406.96 | 2712.49 | 88.74 |
| M_D_DQ_15 | 2409.77 | 2451.7199999999998 | 98.29 |
| M_D_DQ_16 | 2221.9899999999998 | 2562.3000000000002 | 86.72 |
| M_D_DQ_17 | 2224.21 | 2356.2399999999998 | 94.4 |
| M_D_DQ_18 | 2226.7600000000002 | 2403.86 | 92.63 |
| M_D_DQ_19 | 2228.4699999999998 | 2323.77 | 95.9 |
| M_D_DQ_20 | 2220.9899999999998 | 2574.5300000000002 | 86.27 |
| M_D_DQ_21 | 2226.7600000000002 | 2368.46 | 94.02 |
| M_D_DQ_22 | 2226.0300000000002 | 2456.09 | 90.63 |
| M_D_DQ_23 | 2227.27 | 2376 | 93.74 |
| M_D_DQ_24 | 2033.03 | 2259.4 | 89.98 |
| M_D_DQ_25 | 2035.27 | 2154.0100000000002 | 94.49 |
| M_D_DQ_26 | 2038.05 | 2226.94 | 91.52 |
| M_D_DQ_27 | 2035.59 | 1995.57 | 102.01 |
| M_D_DQ_28 | 2038.18 | 2311.63 | 88.17 |
| M_D_DQ_29 | 2039.43 | 2151.54 | 94.79 |
| M_D_DQ_30 | 2037.62 | 2199.17 | 92.65 |
| M_D_DQ_31 | 2037.01 | 1967.8 | 103.52 |
| M_D_DQ_32 | 2163.3200000000002 | 2344.0100000000002 | 92.29 |
| M_D_DQ_33 | 2154.29 | 2124.87 | 101.38 |
| M_D_DQ_34 | 2157.87 | 2391.17 | 90.24 |
| M_D_DQ_35 | 2159.5100000000002 | 2378.0100000000002 | 90.81 |
| M_D_DQ_36 | 2156.92 | 2357.08 | 91.51 |
| M_D_DQ_37 | 2159.69 | 2123.2399999999998 | 101.72 |
| M_D_DQ_38 | 2158.3200000000002 | 2378.94 | 90.73 |
| M_D_DQ_39 | 2158.14 | 2460.48 | 87.71 |
| M_D_DQ_40 | 2388.8000000000002 | 2722.63 | 87.74 |
| M_D_DQ_41 | 2386.9299999999998 | 2654.77 | 89.91 |
| M_D_DQ_42 | 2390.15 | 2881.07 | 82.96 |
| M_D_DQ_43 | 2389.91 | 2756.63 | 86.7 |
| M_D_DQ_44 | 2386.73 | 2615.6999999999998 | 91.25 |
| M_D_DQ_45 | 2387.8200000000002 | 2522.54 | 94.66 |
| M_D_DQ_46 | 2390.2399999999998 | 2828.84 | 84.5 |
| M_D_DQ_47 | 2387.89 | 2744.41 | 87.01 |
| M_D_DQ_48 | 3063.8 | 3436.14 | 89.16 |
| M_D_DQ_49 | 3062.95 | 3187.6 | 96.09 |
| M_D_DQ_50 | 3068.27 | 3687.4 | 83.21 |
| M_D_DQ_51 | 3068.4 | 3703.64 | 82.85 |
| M_D_DQ_52 | 3071.34 | 3438.61 | 89.32 |
| M_D_DQ_53 | 3065.44 | 3150.07 | 97.31 |
| M_D_DQ_54 | 3067.22 | 3580.47 | 85.67 |
| M_D_DQ_55 | 3066.59 | 3497.92 | 87.67 |
| M_D_DQ_56 | 3307.26 | 3545.35 | 93.28 |
| M_D_DQ_57 | 3313.13 | 3477.49 | 95.27 |
| M_D_DQ_58 | 3314.64 | 3977.29 | 83.34 |
| M_D_DQ_59 | 3313.32 | 3838.15 | 86.33 |
| M_D_DQ_60 | 3311.26 | 3493.12 | 94.79 |
| M_D_DQ_61 | 3310.9 | 3494.66 | 94.74 |
| M_D_DQ_62 | 3310.9 | 3840.96 | 86.2 |
| M_D_DQ_63 | 3309.58 | 3745.93 | 88.35 |
| M_D_ECC_0 | 1957.43 | 2088.98 | 93.7 |
| M_D_ECC_1 | 1952.17 | 1802.91 | 108.28 |
| M_D_ECC_2 | 1952.9 | 1930.54 | 101.16 |
| M_D_ECC_3 | 1954.14 | 1770.45 | 110.38 |
| M_D_ECC_4 | 1954.79 | 2101.21 | 93.03 |
| M_D_ECC_5 | 1953.29 | 1895.14 | 103.07 |
| M_D_ECC_6 | 1952.11 | 1982.77 | 98.45 |
| M_D_ECC_7 | 1953.21 | 1822.68 | 107.16 |
| M_D_MA_0 | 1876.52 | 2063.35 | 90.95 |
| M_D_MA_1 | 1875.53 | 1660.02 | 112.98 |
| M_D_MA_2 | 1872.64 | 1430.41 | 130.91999999999999 |
| M_D_MA_3 | 1878.06 | 1664.24 | 112.85 |
| M_D_MA_4 | 1875.31 | 1480.62 | 126.66 |
| M_D_MA_5 | 1869.4 | 1562.38 | 119.65 |
| M_D_MA_6 | 1876.42 | 1631.99 | 114.98 |
| M_D_MA_7 | 1881.19 | 1574.61 | 119.47 |
| M_D_MA_8 | 1873.69 | 1587.76 | 118.01 |
| M_D_MA_9 | 1875.06 | 1599.99 | 117.19 |
| M_D_MA_10 | 1870.17 | 1991.26 | 93.92 |
| M_D_MA_11 | 1861.26 | 1530.38 | 121.62 |
| M_D_MA_12 | 1875.56 | 1816.45 | 103.25 |
| M_D_MA_13 | 1872.32 | 2147.83 | 87.17 |
| M_D_MA_14 | 1872.67 | 1973.97 | 94.87 |
| M_D_MA_15 | 1874.51 | 2110.5100000000002 | 88.82 |
| M_D_MA_16 | 1871.22 | 2071.35 | 90.34 |
| M_D_MA_17 | 1874 | 2160.06 | 86.76 |
| M_D_ODT_0 | 1934.68 | 2305.7600000000002 | 83.91 |
| M_D_ODT_1 | 1914.28 | 2275.52 | 84.12 |
| M_D_ODT_2 | 1924.4 | 1865.27 | 103.17 |
| M_D_ODT_3 | 1941.58 | 1929.73 | 100.61 |
| M_D_PAR | 1871.85 | 1857.28 | 100.78 |
| M_EF_CPU_VREF | 4217.25 | 4196.53 | 100.49 |
| M_EF_RESET_N | 2623.53 | 2686.71 | 97.65 |
| M_EF_VREF | 1885.96 | 1753.09 | 107.58 |
| M_E_ACT_N | 3041.81 | 2847.55 | 106.82 |
| M_E_ALERT_N | 2846.07 | 2751.01 | 103.46 |
| M_E_BA_0 | 3048.3 | 2902.53 | 105.02 |
| M_E_BA_1 | 3042.4 | 2751.17 | 110.59 |
| M_E_BG_0 | 3064.45 | 2891.78 | 105.97 |
| M_E_BG_1 | 3046.62 | 2702.17 | 112.75 |
| M_E_CKE_0 | 2999.65 | 2969.18 | 101.03 |
| M_E_CKE_1 | 3000.04 | 2996.02 | 100.13 |
| M_E_CKE_2 | 2685.46 | 2623.39 | 102.37 |
| M_E_CKE_3 | 2684.86 | 2664.93 | 100.75 |
| M_E_CLK_DN_0 | 3010.17 | 2749 | 109.5 |
| M_E_CLK_DN_1 | 2691.25 | 2333.9699999999998 | 115.31 |
| M_E_CLK_DN_2 | 3009.75 | 2544.69 | 118.28 |
| M_E_CLK_DN_3 | 2691.39 | 2169.66 | 124.05 |
| M_E_CLK_DP_0 | 3009.63 | 2759.48 | 109.07 |
| M_E_CLK_DP_1 | 2691.12 | 2277.5100000000002 | 118.16 |
| M_E_CLK_DP_2 | 3009.68 | 2555.17 | 117.79 |
| M_E_CLK_DP_3 | 2691.14 | 2169.38 | 124.05 |
| M_E_CS_N_0 | 3010.76 | 3045.24 | 98.87 |
| M_E_CS_N_1 | 3015.19 | 3195.55 | 94.36 |
| M_E_CS_N_2 | 3043.05 | 3230.61 | 94.19 |
| M_E_CS_N_3 | 3051.98 | 3175.7 | 96.1 |
| M_E_CS_N_4 | 2705.78 | 2554.15 | 105.94 |
| M_E_CS_N_5 | 2697.81 | 2755.06 | 97.92 |
| M_E_CS_N_6 | 2661.95 | 2819.52 | 94.41 |
| M_E_CS_N_7 | 2675.43 | 2749.91 | 97.29 |
| M_E_C_2 | 3048.11 | 2988.77 | 101.99 |
| M_E_DQS_DN_0 | 4324.75 | 4398.03 | 98.33 |
| M_E_DQS_DN_1 | 4270.47 | 4246.41 | 100.57 |
| M_E_DQS_DN_2 | 3728.16 | 3655.31 | 101.99 |
| M_E_DQS_DN_3 | 3452.95 | 3379.59 | 102.17 |
| M_E_DQS_DN_4 | 3103.24 | 2993.46 | 103.67 |
| M_E_DQS_DN_5 | 3362.03 | 3544.56 | 94.85 |
| M_E_DQS_DN_6 | 3484.69 | 3626.78 | 96.08 |
| M_E_DQS_DN_7 | 3597.24 | 3937.88 | 91.35 |
| M_E_DQS_DN_8 | 3065.39 | 2704.39 | 113.35 |
| M_E_DQS_DN_9 | 4321.6499999999996 | 4631.74 | 93.31 |
| M_E_DQS_DN_10 | 4273.6000000000004 | 4520.12 | 94.55 |
| M_E_DQS_DN_11 | 3728.25 | 3680.82 | 101.29 |
| M_E_DQS_DN_12 | 3448.22 | 3623.9 | 95.15 |
| M_E_DQS_DN_13 | 3109.76 | 3237.77 | 96.05 |
| M_E_DQS_DN_14 | 3364.92 | 3788.87 | 88.81 |
| M_E_DQS_DN_15 | 3490.16 | 3831.09 | 91.1 |
| M_E_DQS_DN_16 | 3596.79 | 4142.1899999999996 | 86.83 |
| M_E_DQS_DN_17 | 3070.66 | 2759.3 | 111.28 |
| M_E_DQS_DP_0 | 4322.3599999999997 | 4387.55 | 98.51 |
| M_E_DQS_DP_1 | 4268.51 | 4204.6499999999996 | 101.52 |
| M_E_DQS_DP_2 | 3730.18 | 3630.13 | 102.76 |
| M_E_DQS_DP_3 | 3453.46 | 3297.83 | 104.72 |
| M_E_DQS_DP_4 | 3102.68 | 3129.92 | 99.13 |
| M_E_DQS_DP_5 | 3359.55 | 3555.04 | 94.5 |
| M_E_DQS_DP_6 | 3480.81 | 3763.24 | 92.5 |
| M_E_DQS_DP_7 | 3596.42 | 3948.36 | 91.09 |
| M_E_DQS_DP_8 | 3065.87 | 2693.91 | 113.81 |
| M_E_DQS_DP_9 | 4321.1099999999997 | 4713.49 | 91.68 |
| M_E_DQS_DP_10 | 4270.33 | 4475.8900000000003 | 95.41 |
| M_E_DQS_DP_11 | 3730.49 | 3831.97 | 97.35 |
| M_E_DQS_DP_12 | 3447.97 | 3539.67 | 97.41 |
| M_E_DQS_DP_13 | 3108.89 | 3227.3 | 96.33 |
| M_E_DQS_DP_14 | 3364 | 3652.42 | 92.1 |
| M_E_DQS_DP_15 | 3491.58 | 3820.62 | 91.39 |
| M_E_DQS_DP_16 | 3595.7 | 4005.74 | 89.76 |
| M_E_DQS_DP_17 | 3070.63 | 2895.75 | 106.04 |
| M_E_DQ_0 | 4322.63 | 4765.72 | 90.7 |
| M_E_DQ_1 | 4316.8599999999997 | 4504.96 | 95.82 |
| M_E_DQ_2 | 4321.6899999999996 | 4457.88 | 96.94 |
| M_E_DQ_3 | 4325.74 | 4283.09 | 101 |
| M_E_DQ_4 | 4323.8999999999996 | 4887.3500000000004 | 88.47 |
| M_E_DQ_5 | 4319.2299999999996 | 4655.9799999999996 | 92.77 |
| M_E_DQ_6 | 4322.95 | 4455.41 | 97.03 |
| M_E_DQ_7 | 4321.84 | 4280.62 | 100.96 |
| M_E_DQ_8 | 4268.0600000000004 | 4528.12 | 94.26 |
| M_E_DQ_9 | 4264.5600000000004 | 4353.34 | 97.96 |
| M_E_DQ_10 | 4263.05 | 4331.5600000000004 | 98.42 |
| M_E_DQ_11 | 4269.8100000000004 | 4100.1899999999996 | 104.14 |
| M_E_DQ_12 | 4266.01 | 4664.45 | 91.46 |
| M_E_DQ_13 | 4267.68 | 4559.0600000000004 | 93.61 |
| M_E_DQ_14 | 4267.1099999999997 | 4289.09 | 99.49 |
| M_E_DQ_15 | 4267.2700000000004 | 4097.72 | 104.14 |
| M_E_DQ_16 | 3730.31 | 3938.9 | 94.7 |
| M_E_DQ_17 | 3727.48 | 3638.14 | 102.46 |
| M_E_DQ_18 | 3731.01 | 3576.36 | 104.32 |
| M_E_DQ_19 | 3728.92 | 3510.97 | 106.21 |
| M_E_DQ_20 | 3727.22 | 4060.53 | 91.79 |
| M_E_DQ_21 | 3727.76 | 3829.16 | 97.35 |
| M_E_DQ_22 | 3730.2 | 3573.89 | 104.37 |
| M_E_DQ_23 | 3731.5 | 3508.5 | 106.36 |
| M_E_DQ_24 | 3420.27 | 3646.6 | 93.79 |
| M_E_DQ_25 | 3416.04 | 3555.91 | 96.07 |
| M_E_DQ_26 | 3414.81 | 3370.04 | 101.33 |
| M_E_DQ_27 | 3423.71 | 3203.97 | 106.86 |
| M_E_DQ_28 | 3420.88 | 3753.53 | 91.14 |
| M_E_DQ_29 | 3416.35 | 3648.14 | 93.65 |
| M_E_DQ_30 | 3416.77 | 3367.57 | 101.46 |
| M_E_DQ_31 | 3420.88 | 3176.2 | 107.7 |
| M_E_DQ_32 | 3094.31 | 3215.07 | 96.24 |
| M_E_DQ_33 | 3095.57 | 3075.93 | 100.64 |
| M_E_DQ_34 | 3097.36 | 3247.53 | 95.38 |
| M_E_DQ_35 | 3101 | 3234.37 | 95.88 |
| M_E_DQ_36 | 3097.93 | 3162.84 | 97.95 |
| M_E_DQ_37 | 3096.67 | 3023.7 | 102.41 |
| M_E_DQ_38 | 3100.14 | 3195.3 | 97.02 |
| M_E_DQ_39 | 3099.93 | 3182.14 | 97.42 |
| M_E_DQ_40 | 3361.31 | 3640.19 | 92.34 |
| M_E_DQ_41 | 3359.57 | 3627.03 | 92.63 |
| M_E_DQ_42 | 3365.05 | 3798.63 | 88.59 |
| M_E_DQ_43 | 3367.82 | 3659.49 | 92.03 |
| M_E_DQ_44 | 3365.06 | 3587.96 | 93.79 |
| M_E_DQ_45 | 3360.41 | 3574.8 | 94 |
| M_E_DQ_46 | 3364.34 | 3746.4 | 89.8 |
| M_E_DQ_47 | 3361.52 | 3607.27 | 93.19 |
| M_E_DQ_48 | 3480.12 | 3808.39 | 91.38 |
| M_E_DQ_49 | 3478.32 | 3669.25 | 94.8 |
| M_E_DQ_50 | 3478.51 | 3840.85 | 90.57 |
| M_E_DQ_51 | 3483.01 | 3827.69 | 91 |
| M_E_DQ_52 | 3483.99 | 3756.16 | 92.75 |
| M_E_DQ_53 | 3476.42 | 3617.02 | 96.11 |
| M_E_DQ_54 | 3477.68 | 3788.62 | 91.79 |
| M_E_DQ_55 | 3478.4 | 3775.47 | 92.13 |
| M_E_DQ_56 | 3600.3 | 3993.51 | 90.15 |
| M_E_DQ_57 | 3598.71 | 3980.35 | 90.41 |
| M_E_DQ_58 | 3600.77 | 4151.95 | 86.72 |
| M_E_DQ_59 | 3602.65 | 4012.81 | 89.78 |
| M_E_DQ_60 | 3599.09 | 3941.28 | 91.32 |
| M_E_DQ_61 | 3598.14 | 3928.12 | 91.6 |
| M_E_DQ_62 | 3600.09 | 4099.72 | 87.81 |
| M_E_DQ_63 | 3596.3 | 3960.59 | 90.8 |
| M_E_ECC_0 | 3069.93 | 2947.98 | 104.14 |
| M_E_ECC_1 | 3067.12 | 2661.91 | 115.22 |
| M_E_ECC_2 | 3068.38 | 2694.84 | 113.86 |
| M_E_ECC_3 | 3069.52 | 2614.75 | 117.39 |
| M_E_ECC_4 | 3068.82 | 3054.91 | 100.46 |
| M_E_ECC_5 | 3070.25 | 2863.54 | 107.22 |
| M_E_ECC_6 | 3070.59 | 2827.07 | 108.61 |
| M_E_ECC_7 | 3064.9 | 2721.68 | 112.61 |
| M_E_MA_0 | 3044.56 | 2740.91 | 111.08 |
| M_E_MA_1 | 3046.56 | 2586.4 | 117.79 |
| M_E_MA_2 | 3046.18 | 2451.4899999999998 | 124.26 |
| M_E_MA_3 | 3045.68 | 2722.86 | 111.86 |
| M_E_MA_4 | 3050.33 | 2489.02 | 122.55 |
| M_E_MA_5 | 3044.98 | 2610.7800000000002 | 116.63 |
| M_E_MA_6 | 3051.49 | 2720.39 | 112.17 |
| M_E_MA_7 | 3032.61 | 2703.01 | 112.19 |
| M_E_MA_8 | 3048.05 | 2770.86 | 110 |
| M_E_MA_9 | 3045.57 | 2783.09 | 109.43 |
| M_E_MA_10 | 3047.22 | 2588.8200000000002 | 117.71 |
| M_E_MA_11 | 3048.6 | 2553.48 | 119.39 |
| M_E_MA_12 | 3047.38 | 2744.85 | 111.02 |
| M_E_MA_13 | 3042.64 | 2974.79 | 102.28 |
| M_E_MA_14 | 3044.5 | 2830.33 | 107.57 |
| M_E_MA_15 | 3046.99 | 2868.07 | 106.24 |
| M_E_MA_16 | 3052.32 | 2803.61 | 108.87 |
| M_E_MA_17 | 3054.62 | 3027.02 | 100.91 |
| M_E_ODT_0 | 3022.75 | 3168.62 | 95.4 |
| M_E_ODT_1 | 2996.69 | 3058.38 | 97.98 |
| M_E_ODT_2 | 2701.33 | 2702.83 | 99.94 |
| M_E_ODT_3 | 2706.67 | 2956.69 | 91.54 |
| M_E_PAR | 3044.81 | 2644.24 | 115.15 |
| M_F_ACT_N | 1994.58 | 1985.37 | 100.46 |
| M_F_ALERT_N | 1740.46 | 1754.13 | 99.22 |
| M_F_BA_0 | 1981.26 | 1930.95 | 102.61 |
| M_F_BA_1 | 1982.09 | 1739.59 | 113.94 |
| M_F_BG_0 | 1994.59 | 1974.9 | 101 |
| M_F_BG_1 | 1988.27 | 1905.29 | 104.36 |
| M_F_CKE_0 | 1972.27 | 1987 | 99.26 |
| M_F_CKE_1 | 1974.61 | 1893.84 | 104.26 |
| M_F_CKE_2 | 1492.07 | 1521.21 | 98.08 |
| M_F_CKE_3 | 1473.68 | 1428.05 | 103.2 |
| M_F_CLK_DN_0 | 1957.42 | 1646.82 | 118.86 |
| M_F_CLK_DN_1 | 1496.8 | 1231.79 | 121.51 |
| M_F_CLK_DN_2 | 1956.15 | 1442.51 | 135.61000000000001 |
| M_F_CLK_DN_3 | 1496.79 | 1067.48 | 140.22 |
| M_F_CLK_DP_0 | 1956.5 | 1577.3 | 124.04 |
| M_F_CLK_DP_1 | 1497.08 | 1095.33 | 136.68 |
| M_F_CLK_DP_2 | 1956.09 | 1372.99 | 142.47 |
| M_F_CLK_DP_3 | 1496.73 | 987.2 | 151.61000000000001 |
| M_F_CS_N_0 | 1975.65 | 1863.06 | 106.04 |
| M_F_CS_N_1 | 1975.4 | 2078.67 | 95.03 |
| M_F_CS_N_2 | 2016.95 | 2288.4299999999998 | 88.14 |
| M_F_CS_N_3 | 1914.39 | 2178.8200000000002 | 87.86 |
| M_F_CS_N_4 | 1492.8 | 1557.27 | 95.86 |
| M_F_CS_N_5 | 1494.94 | 1692.88 | 88.31 |
| M_F_CS_N_6 | 1591.06 | 1837.34 | 86.6 |
| M_F_CS_N_7 | 1499.17 | 1727.73 | 86.77 |
| M_F_C_2 | 1993.45 | 2126.59 | 93.74 |
| M_F_DQS_DN_0 | 3336.44 | 3531.75 | 94.47 |
| M_F_DQS_DN_1 | 2955.6 | 3150.73 | 93.81 |
| M_F_DQS_DN_2 | 2555.59 | 2450.23 | 104.3 |
| M_F_DQS_DN_3 | 2001.98 | 2218.61 | 90.24 |
| M_F_DQS_DN_4 | 2037.05 | 2131.2800000000002 | 95.58 |
| M_F_DQS_DN_5 | 2372.62 | 2412.98 | 98.33 |
| M_F_DQS_DN_6 | 2391.87 | 2644.6 | 90.44 |
| M_F_DQS_DN_7 | 2699.57 | 2995.7 | 90.11 |
| M_F_DQS_DN_8 | 2375.4 | 1966.31 | 120.8 |
| M_F_DQS_DN_9 | 3358.34 | 3611.96 | 92.98 |
| M_F_DQS_DN_10 | 2956.47 | 3216.24 | 91.92 |
| M_F_DQS_DN_11 | 2552.88 | 2585.14 | 98.75 |
| M_F_DQS_DN_12 | 2000.09 | 2313.52 | 86.45 |
| M_F_DQS_DN_13 | 2078.4699999999998 | 2375.59 | 87.49 |
| M_F_DQS_DN_14 | 2376.2800000000002 | 2602.59 | 91.3 |
| M_F_DQS_DN_15 | 2426.15 | 2848.91 | 85.16 |
| M_F_DQS_DN_16 | 2698.24 | 3065.31 | 88.02 |
| M_F_DQS_DN_17 | 2381.9299999999998 | 2170.62 | 109.73 |
| M_F_DQS_DP_0 | 3336.78 | 3575.97 | 93.31 |
| M_F_DQS_DP_1 | 2956.61 | 2999.57 | 98.57 |
| M_F_DQS_DP_2 | 2553.1799999999998 | 2519.75 | 101.33 |
| M_F_DQS_DP_3 | 2000.87 | 2176.85 | 91.92 |
| M_F_DQS_DP_4 | 2037.72 | 2267.7399999999998 | 89.86 |
| M_F_DQS_DP_5 | 2370.9 | 2343.46 | 101.17 |
| M_F_DQS_DP_6 | 2392.7399999999998 | 2781.06 | 86.04 |
| M_F_DQS_DP_7 | 2697.65 | 2911.48 | 92.66 |
| M_F_DQS_DP_8 | 2376.96 | 2010.53 | 118.23 |
| M_F_DQS_DP_9 | 3356.21 | 3763.11 | 89.19 |
| M_F_DQS_DP_10 | 2954.03 | 3201.41 | 92.27 |
| M_F_DQS_DP_11 | 2553.0100000000002 | 2641.59 | 96.65 |
| M_F_DQS_DP_12 | 1998.26 | 2269.29 | 88.06 |
| M_F_DQS_DP_13 | 2078.33 | 2365.12 | 87.87 |
| M_F_DQS_DP_14 | 2375.5300000000002 | 2520.84 | 94.24 |
| M_F_DQS_DP_15 | 2427 | 2838.44 | 85.5 |
| M_F_DQS_DP_16 | 2697.89 | 3023.56 | 89.23 |
| M_F_DQS_DP_17 | 2381.7800000000002 | 2252.37 | 105.75 |
| M_F_DQ_0 | 3379.92 | 3899.44 | 86.68 |
| M_F_DQ_1 | 3378.25 | 3569.28 | 94.65 |
| M_F_DQ_2 | 3377.65 | 3507.5 | 96.3 |
| M_F_DQ_3 | 3380.4 | 3402.11 | 99.36 |
| M_F_DQ_4 | 3380.26 | 4006.37 | 84.37 |
| M_F_DQ_5 | 3379.16 | 3690.9 | 91.55 |
| M_F_DQ_6 | 3386.01 | 3505.03 | 96.6 |
| M_F_DQ_7 | 3378.86 | 3439.64 | 98.23 |
| M_F_DQ_8 | 2955.6 | 3293.64 | 89.74 |
| M_F_DQ_9 | 2958.95 | 3188.26 | 92.81 |
| M_F_DQ_10 | 2956.19 | 3071.78 | 96.24 |
| M_F_DQ_11 | 2953.59 | 2771.01 | 106.59 |
| M_F_DQ_12 | 2962.21 | 3429.97 | 86.36 |
| M_F_DQ_13 | 2961.43 | 3324.58 | 89.08 |
| M_F_DQ_14 | 2955.92 | 3193.41 | 92.56 |
| M_F_DQ_15 | 2954.73 | 2823.24 | 104.66 |
| M_F_DQ_16 | 2564.31 | 2788.52 | 91.96 |
| M_F_DQ_17 | 2564.3200000000002 | 2447.7600000000002 | 104.76 |
| M_F_DQ_18 | 2558.25 | 2575.38 | 99.33 |
| M_F_DQ_19 | 2557.4 | 2495.29 | 102.49 |
| M_F_DQ_20 | 2563.17 | 2786.05 | 92 |
| M_F_DQ_21 | 2563.39 | 2594.6799999999998 | 98.79 |
| M_F_DQ_22 | 2558.84 | 2587.61 | 98.89 |
| M_F_DQ_23 | 2559.81 | 2507.52 | 102.09 |
| M_F_DQ_24 | 1985.94 | 2376.2199999999998 | 83.58 |
| M_F_DQ_25 | 1986.9 | 2270.83 | 87.5 |
| M_F_DQ_26 | 1987.06 | 2263.7600000000002 | 87.78 |
| M_F_DQ_27 | 1989.24 | 2057.69 | 96.67 |
| M_F_DQ_28 | 1994.62 | 2373.75 | 84.03 |
| M_F_DQ_29 | 1985.33 | 2308.36 | 86.01 |
| M_F_DQ_30 | 1987.56 | 2261.29 | 87.89 |
| M_F_DQ_31 | 1987.12 | 2029.92 | 97.89 |
| M_F_DQ_32 | 2081.08 | 2352.89 | 88.45 |
| M_F_DQ_33 | 2081.09 | 2213.75 | 94.01 |
| M_F_DQ_34 | 2081.21 | 2385.35 | 87.25 |
| M_F_DQ_35 | 2081.39 | 2372.19 | 87.74 |
| M_F_DQ_36 | 2080.9299999999998 | 2300.66 | 90.45 |
| M_F_DQ_37 | 2077.64 | 2161.52 | 96.12 |
| M_F_DQ_38 | 2081.1 | 2333.12 | 89.2 |
| M_F_DQ_39 | 2080.79 | 2319.96 | 89.69 |
| M_F_DQ_40 | 2373.44 | 2523.31 | 94.06 |
| M_F_DQ_41 | 2372.7199999999998 | 2415.4499999999998 | 98.23 |
| M_F_DQ_42 | 2371.37 | 2641.75 | 89.77 |
| M_F_DQ_43 | 2375.84 | 2367.91 | 100.33 |
| M_F_DQ_44 | 2375.4499999999998 | 2471.08 | 96.13 |
| M_F_DQ_45 | 2379.27 | 2457.92 | 96.8 |
| M_F_DQ_46 | 2375.08 | 2614.8200000000002 | 90.83 |
| M_F_DQ_47 | 2373.88 | 2355.69 | 100.77 |
| M_F_DQ_48 | 2403.85 | 2826.21 | 85.06 |
| M_F_DQ_49 | 2404.41 | 2687.07 | 89.48 |
| M_F_DQ_50 | 2401.7800000000002 | 2858.67 | 84.02 |
| M_F_DQ_51 | 2403.6799999999998 | 2845.51 | 84.47 |
| M_F_DQ_52 | 2402.44 | 2773.98 | 86.61 |
| M_F_DQ_53 | 2401.64 | 2634.84 | 91.15 |
| M_F_DQ_54 | 2401.17 | 2806.44 | 85.56 |
| M_F_DQ_55 | 2401.65 | 2793.29 | 85.98 |
| M_F_DQ_56 | 2696.3 | 2941.93 | 91.65 |
| M_F_DQ_57 | 2691.39 | 2863.47 | 93.99 |
| M_F_DQ_58 | 2697.7 | 3169.77 | 85.11 |
| M_F_DQ_59 | 2695.76 | 3030.63 | 88.95 |
| M_F_DQ_60 | 2694.45 | 2944.4 | 91.51 |
| M_F_DQ_61 | 2697.84 | 2876.54 | 93.79 |
| M_F_DQ_62 | 2699.05 | 3077.54 | 87.7 |
| M_F_DQ_63 | 2696.66 | 2883.71 | 93.51 |
| M_F_ECC_0 | 2379.16 | 2359.3000000000002 | 100.84 |
| M_F_ECC_1 | 2379.96 | 2127.9299999999998 | 111.84 |
| M_F_ECC_2 | 2374.79 | 1956.76 | 121.36 |
| M_F_ECC_3 | 2379.94 | 1796.67 | 132.46 |
| M_F_ECC_4 | 2382.7199999999998 | 2466.23 | 96.61 |
| M_F_ECC_5 | 2381.56 | 2234.86 | 106.56 |
| M_F_ECC_6 | 2377.29 | 2008.99 | 118.33 |
| M_F_ECC_7 | 2376.58 | 1848.9 | 128.54 |
| M_F_MA_0 | 1988.36 | 1878.73 | 105.84 |
| M_F_MA_1 | 1989.75 | 1724.22 | 115.4 |
| M_F_MA_2 | 1989.48 | 1599.91 | 124.35 |
| M_F_MA_3 | 1978.36 | 1860.68 | 106.32 |
| M_F_MA_4 | 1976.85 | 1692.14 | 116.83 |
| M_F_MA_5 | 1965.75 | 1723.3 | 114.07 |
| M_F_MA_6 | 1986.23 | 1858.21 | 106.89 |
| M_F_MA_7 | 1986.79 | 1800.83 | 110.33 |
| M_F_MA_8 | 1980.74 | 1788.68 | 110.74 |
| M_F_MA_9 | 1982 | 1840.91 | 107.66 |
| M_F_MA_10 | 1989.52 | 1861.34 | 106.89 |
| M_F_MA_11 | 1978.85 | 1731.3 | 114.3 |
| M_F_MA_12 | 1979.8 | 1922.67 | 102.97 |
| M_F_MA_13 | 1988.15 | 1883.21 | 105.57 |
| M_F_MA_14 | 1980.76 | 1938.75 | 102.17 |
| M_F_MA_15 | 1980.38 | 2020.59 | 98.01 |
| M_F_MA_16 | 1988.05 | 1846.73 | 107.65 |
| M_F_MA_17 | 1996.06 | 2044.84 | 97.61 |
| M_F_ODT_0 | 1973.16 | 2066.44 | 95.49 |
| M_F_ODT_1 | 1973.13 | 2076.1999999999998 | 95.04 |
| M_F_ODT_2 | 1500.19 | 1680.65 | 89.26 |
| M_F_ODT_3 | 1510.53 | 1745.11 | 86.56 |
| M_F_PAR | 1984.24 | 1782.06 | 111.35 |
| M_GH_CPU_VREF | 2105.5100000000002 | 2555.79 | 82.38 |
| M_GH_RESET_N | 2590.21 | 2670.96 | 96.98 |
| M_GH_VREF | 1840.27 | 2016.21 | 91.27 |
| M_G_ACT_N | 3040.91 | 3046.5 | 99.82 |
| M_G_ALERT_N | 2607.36 | 2575.2600000000002 | 101.25 |
| M_G_BA_0 | 3041.51 | 2706.24 | 112.39 |
| M_G_BA_1 | 3047.89 | 2664.28 | 114.4 |
| M_G_BG_0 | 3046.91 | 2996.03 | 101.7 |
| M_G_BG_1 | 3054.04 | 2941.12 | 103.84 |
| M_G_CKE_0 | 2910.41 | 2913.43 | 99.9 |
| M_G_CKE_1 | 2917 | 2900.27 | 100.58 |
| M_G_CKE_2 | 2603.5700000000002 | 2527.64 | 103 |
| M_G_CKE_3 | 2612.34 | 2554.48 | 102.26 |
| M_G_CLK_DN_0 | 2932.62 | 2693.25 | 108.89 |
| M_G_CLK_DN_1 | 2625.56 | 2301.7800000000002 | 114.07 |
| M_G_CLK_DN_2 | 2932.68 | 2528.94 | 115.96 |
| M_G_CLK_DN_3 | 2625.35 | 2103.15 | 124.83 |
| M_G_CLK_DP_0 | 2932.44 | 2703.73 | 108.46 |
| M_G_CLK_DP_1 | 2626.31 | 2248.54 | 116.8 |
| M_G_CLK_DP_2 | 2932.66 | 2539.42 | 115.49 |
| M_G_CLK_DP_3 | 2625.08 | 2113.63 | 124.2 |
| M_G_CS_N_0 | 2907.67 | 3013.05 | 96.5 |
| M_G_CS_N_1 | 2909.97 | 3123.36 | 93.17 |
| M_G_CS_N_2 | 3021.91 | 3213.12 | 94.05 |
| M_G_CS_N_3 | 2954.94 | 3103.51 | 95.21 |
| M_G_CS_N_4 | 2637.56 | 2481.96 | 106.27 |
| M_G_CS_N_5 | 2605.11 | 2737.57 | 95.16 |
| M_G_CS_N_6 | 2680.57 | 2922.03 | 91.74 |
| M_G_CS_N_7 | 2668.19 | 2896.52 | 92.12 |
| M_G_C_2 | 3042.14 | 2956.58 | 102.89 |
| M_G_DQS_DN_0 | 4042.84 | 4028.78 | 100.35 |
| M_G_DQS_DN_1 | 3432.88 | 3877.16 | 88.54 |
| M_G_DQS_DN_2 | 3503.79 | 3566.06 | 98.25 |
| M_G_DQS_DN_3 | 3197.63 | 3403.84 | 93.94 |
| M_G_DQS_DN_4 | 3121.84 | 2961.27 | 105.42 |
| M_G_DQS_DN_5 | 3573.75 | 3581.77 | 99.78 |
| M_G_DQS_DN_6 | 3987.1 | 4221.6000000000004 | 94.45 |
| M_G_DQS_DN_7 | 4233.82 | 4459.2 | 94.95 |
| M_G_DQS_DN_8 | 3258.13 | 3092.74 | 105.35 |
| M_G_DQS_DN_9 | 4038.26 | 4258.3900000000003 | 94.83 |
| M_G_DQS_DN_10 | 3430.82 | 3932.07 | 87.25 |
| M_G_DQS_DN_11 | 3522.52 | 3620.97 | 97.28 |
| M_G_DQS_DN_12 | 3198.41 | 3458.75 | 92.47 |
| M_G_DQS_DN_13 | 3122.18 | 3016.18 | 103.51 |
| M_G_DQS_DN_14 | 3574.32 | 3676.68 | 97.22 |
| M_G_DQS_DN_15 | 3986.2 | 4440.6099999999997 | 89.77 |
| M_G_DQS_DN_16 | 4233.91 | 4663.51 | 90.79 |
| M_G_DQS_DN_17 | 3257.27 | 3147.65 | 103.48 |
| M_G_DQS_DP_0 | 4039.35 | 4003.6 | 100.89 |
| M_G_DQS_DP_1 | 3431.31 | 3795.4 | 90.41 |
| M_G_DQS_DP_2 | 3501.77 | 3555.58 | 98.49 |
| M_G_DQS_DP_3 | 3197.68 | 3267.38 | 97.87 |
| M_G_DQS_DP_4 | 3123.21 | 3003.03 | 104 |
| M_G_DQS_DP_5 | 3573.98 | 3592.25 | 99.49 |
| M_G_DQS_DP_6 | 3986.1 | 4263.3599999999997 | 93.5 |
| M_G_DQS_DP_7 | 4233.93 | 4414.9799999999996 | 95.9 |
| M_G_DQS_DP_8 | 3258.32 | 3082.26 | 105.71 |
| M_G_DQS_DP_9 | 4038.71 | 4300.1400000000003 | 93.92 |
| M_G_DQS_DP_10 | 3431.35 | 3887.84 | 88.26 |
| M_G_DQS_DP_11 | 3521.01 | 3757.42 | 93.71 |
| M_G_DQS_DP_12 | 3197.01 | 3469.22 | 92.15 |
| M_G_DQS_DP_13 | 3123.47 | 3100.41 | 100.74 |
| M_G_DQS_DP_14 | 3573.87 | 3525.53 | 101.37 |
| M_G_DQS_DP_15 | 3985.65 | 4484.84 | 88.87 |
| M_G_DQS_DP_16 | 4233.63 | 4581.76 | 92.4 |
| M_G_DQS_DP_17 | 3257.85 | 3284.1 | 99.2 |
| M_G_DQ_0 | 4036.34 | 4407.07 | 91.59 |
| M_G_DQ_1 | 4039.13 | 4135.71 | 97.66 |
| M_G_DQ_2 | 4039.94 | 3964.53 | 101.9 |
| M_G_DQ_3 | 4041.28 | 3909.74 | 103.36 |
| M_G_DQ_4 | 4040.15 | 4528.7 | 89.21 |
| M_G_DQ_5 | 4033.51 | 4173.2299999999996 | 96.65 |
| M_G_DQ_6 | 4040.85 | 4016.76 | 100.6 |
| M_G_DQ_7 | 4038.67 | 3951.37 | 102.21 |
| M_G_DQ_8 | 3436.19 | 3994.77 | 86.02 |
| M_G_DQ_9 | 3431.83 | 3889.39 | 88.24 |
| M_G_DQ_10 | 3430.17 | 3962.31 | 86.57 |
| M_G_DQ_11 | 3431.43 | 3676.24 | 93.34 |
| M_G_DQ_12 | 3433.75 | 4007 | 85.69 |
| M_G_DQ_13 | 3433.49 | 3846.91 | 89.25 |
| M_G_DQ_14 | 3429.07 | 3919.84 | 87.48 |
| M_G_DQ_15 | 3434.82 | 3768.47 | 91.15 |
| M_G_DQ_16 | 3521 | 3809.65 | 92.42 |
| M_G_DQ_17 | 3521.55 | 3523.59 | 99.94 |
| M_G_DQ_18 | 3513.84 | 3651.21 | 96.24 |
| M_G_DQ_19 | 3520.64 | 3491.12 | 100.85 |
| M_G_DQ_20 | 3520.99 | 3821.88 | 92.13 |
| M_G_DQ_21 | 3521.83 | 3535.81 | 99.6 |
| M_G_DQ_22 | 3519.65 | 3703.44 | 95.04 |
| M_G_DQ_23 | 3518.87 | 3543.35 | 99.31 |
| M_G_DQ_24 | 3201.63 | 3481.45 | 91.96 |
| M_G_DQ_25 | 3197.86 | 3321.36 | 96.28 |
| M_G_DQ_26 | 3204.32 | 3448.99 | 92.91 |
| M_G_DQ_27 | 3198.76 | 3162.92 | 101.13 |
| M_G_DQ_28 | 3200.94 | 3533.68 | 90.58 |
| M_G_DQ_29 | 3195.97 | 3373.59 | 94.74 |
| M_G_DQ_30 | 3196.67 | 3501.22 | 91.3 |
| M_G_DQ_31 | 3198.21 | 3215.15 | 99.47 |
| M_G_DQ_32 | 3122.61 | 3088.18 | 101.11 |
| M_G_DQ_33 | 3121.43 | 2814.34 | 110.91 |
| M_G_DQ_34 | 3123.74 | 3230.04 | 96.71 |
| M_G_DQ_35 | 3125.65 | 3122.18 | 100.11 |
| M_G_DQ_36 | 3117.13 | 2941.25 | 105.98 |
| M_G_DQ_37 | 3121.67 | 2802.11 | 111.4 |
| M_G_DQ_38 | 3124.1 | 3028.41 | 103.16 |
| M_G_DQ_39 | 3121.72 | 3015.25 | 103.53 |
| M_G_DQ_40 | 3575.27 | 3473.3 | 102.94 |
| M_G_DQ_41 | 3571.17 | 3529.54 | 101.18 |
| M_G_DQ_42 | 3573.59 | 3919.94 | 91.16 |
| M_G_DQ_43 | 3574.27 | 3656.7 | 97.75 |
| M_G_DQ_44 | 3576.5 | 3421.07 | 104.54 |
| M_G_DQ_45 | 3575.78 | 3422.61 | 104.48 |
| M_G_DQ_46 | 3573.72 | 3783.61 | 94.45 |
| M_G_DQ_47 | 3575.29 | 3549.78 | 100.72 |
| M_G_DQ_48 | 3983.73 | 4133.8 | 96.37 |
| M_G_DQ_49 | 3986.49 | 4009.36 | 99.43 |
| M_G_DQ_50 | 3987.45 | 4490.37 | 88.8 |
| M_G_DQ_51 | 3988.69 | 4491.91 | 88.8 |
| M_G_DQ_52 | 3986.05 | 4245.67 | 93.88 |
| M_G_DQ_53 | 3986.15 | 4011.83 | 99.36 |
| M_G_DQ_54 | 3987.36 | 4492.84 | 88.75 |
| M_G_DQ_55 | 3981.78 | 4494.3900000000003 | 88.59 |
| M_G_DQ_56 | 4235.8599999999997 | 4409.5200000000004 | 96.06 |
| M_G_DQ_57 | 4236.7299999999996 | 4286.96 | 98.83 |
| M_G_DQ_58 | 4232.47 | 4852.07 | 87.23 |
| M_G_DQ_59 | 4234.3500000000004 | 4658.2299999999996 | 90.9 |
| M_G_DQ_60 | 4235.28 | 4233.1899999999996 | 100.05 |
| M_G_DQ_61 | 4235.3900000000003 | 4249.43 | 99.67 |
| M_G_DQ_62 | 4234.58 | 4715.74 | 89.8 |
| M_G_DQ_63 | 4233.33 | 4521.91 | 93.62 |
| M_G_ECC_0 | 3261.53 | 3296.33 | 98.94 |
| M_G_ECC_1 | 3258.96 | 3010.26 | 108.26 |
| M_G_ECC_2 | 3258.21 | 3137.89 | 103.83 |
| M_G_ECC_3 | 3262.12 | 2977.8 | 109.55 |
| M_G_ECC_4 | 3262.46 | 3348.56 | 97.43 |
| M_G_ECC_5 | 3256.29 | 3062.49 | 106.33 |
| M_G_ECC_6 | 3261.24 | 3190.12 | 102.23 |
| M_G_ECC_7 | 3258.65 | 3030.03 | 107.55 |
| M_G_MA_0 | 3045.63 | 2654.02 | 114.76 |
| M_G_MA_1 | 3049.46 | 2625.35 | 116.15 |
| M_G_MA_2 | 3043.17 | 2486.34 | 122.4 |
| M_G_MA_3 | 3041.59 | 2667.11 | 114.04 |
| M_G_MA_4 | 3044.46 | 2498.5700000000002 | 121.85 |
| M_G_MA_5 | 3047.96 | 2609.73 | 116.79 |
| M_G_MA_6 | 3045.87 | 2719.34 | 112.01 |
| M_G_MA_7 | 3041.66 | 2701.96 | 112.57 |
| M_G_MA_8 | 3044.39 | 2635.11 | 115.53 |
| M_G_MA_9 | 3040.45 | 2727.34 | 111.48 |
| M_G_MA_10 | 3044.11 | 2771.33 | 109.84 |
| M_G_MA_11 | 3050.02 | 2617.73 | 116.51 |
| M_G_MA_12 | 3048.53 | 2889.1 | 105.52 |
| M_G_MA_13 | 3044.28 | 2698.5 | 112.81 |
| M_G_MA_14 | 3043.5 | 2754.04 | 110.51 |
| M_G_MA_15 | 3041.86 | 2835.88 | 107.26 |
| M_G_MA_16 | 3034.33 | 2716.72 | 111.69 |
| M_G_MA_17 | 3045.17 | 2874.83 | 105.93 |
| M_G_ODT_0 | 2935.5 | 3136.43 | 93.59 |
| M_G_ODT_1 | 2953.18 | 3215.59 | 91.84 |
| M_G_ODT_2 | 2606.5700000000002 | 2630.64 | 99.08 |
| M_G_ODT_3 | 2632.92 | 2869.8 | 91.75 |
| M_G_PAR | 3043.07 | 2557.35 | 118.99 |
| M_H_ACT_N | 1949.32 | 2024.32 | 96.3 |
| M_H_ALERT_N | 1787.62 | 1793.08 | 99.7 |
| M_H_BA_0 | 1952.37 | 1829.36 | 106.72 |
| M_H_BA_1 | 1953.15 | 1678 | 116.4 |
| M_H_BG_0 | 1949.18 | 2013.85 | 96.79 |
| M_H_BG_1 | 1946.05 | 1824.24 | 106.68 |
| M_H_CKE_0 | 1835.13 | 1956.55 | 93.79 |
| M_H_CKE_1 | 1840.65 | 1918.09 | 95.96 |
| M_H_CKE_2 | 1457.99 | 1520.16 | 95.91 |
| M_H_CKE_3 | 1460.11 | 1492.3 | 97.84 |
| M_H_CLK_DN_0 | 1824.04 | 1631.07 | 111.83 |
| M_H_CLK_DN_1 | 1471.07 | 1239.5999999999999 | 118.67 |
| M_H_CLK_DN_2 | 1824.2 | 1466.76 | 124.37 |
| M_H_CLK_DN_3 | 1475.76 | 1040.97 | 141.77000000000001 |
| M_H_CLK_DP_0 | 1825.09 | 1561.55 | 116.88 |
| M_H_CLK_DP_1 | 1470.79 | 1106.3599999999999 | 132.94 |
| M_H_CLK_DP_2 | 1823.42 | 1397.24 | 130.5 |
| M_H_CLK_DP_3 | 1475.15 | 971.45 | 151.85 |
| M_H_CS_N_0 | 1839.03 | 1870.87 | 98.3 |
| M_H_CS_N_1 | 1825.35 | 2086.48 | 87.48 |
| M_H_CS_N_2 | 1917.25 | 2106.84 | 91 |
| M_H_CS_N_3 | 1785.21 | 1997.23 | 89.38 |
| M_H_CS_N_4 | 1485.78 | 1445.08 | 102.82 |
| M_H_CS_N_5 | 1474.54 | 1740.69 | 84.71 |
| M_H_CS_N_6 | 1552.38 | 1790.45 | 86.7 |
| M_H_CS_N_7 | 1460.61 | 1520.84 | 96.04 |
| M_H_C_2 | 1936.38 | 1985 | 97.55 |
| M_H_DQS_DN_0 | 2829.73 | 2966.6 | 95.39 |
| M_H_DQS_DN_1 | 2595.6999999999998 | 2760.28 | 94.04 |
| M_H_DQS_DN_2 | 2447.54 | 2543.88 | 96.21 |
| M_H_DQS_DN_3 | 2198.2199999999998 | 2421.66 | 90.77 |
| M_H_DQS_DN_4 | 2057.38 | 1905.59 | 107.97 |
| M_H_DQS_DN_5 | 2165.34 | 2395.4899999999998 | 90.39 |
| M_H_DQS_DN_6 | 3023.29 | 3063.02 | 98.7 |
| M_H_DQS_DN_7 | 3125.36 | 3422.31 | 91.32 |
| M_H_DQS_DN_8 | 2058.04 | 2110.56 | 97.51 |
| M_H_DQS_DN_9 | 2825.87 | 3181.51 | 88.82 |
| M_H_DQS_DN_10 | 2614.75 | 2935.19 | 89.08 |
| M_H_DQS_DN_11 | 2443.75 | 2678.79 | 91.23 |
| M_H_DQS_DN_12 | 2228.86 | 2476.5700000000002 | 90 |
| M_H_DQS_DN_13 | 2057.4499999999998 | 2135.1999999999998 | 96.36 |
| M_H_DQS_DN_14 | 2163.98 | 2599.8000000000002 | 83.24 |
| M_H_DQS_DN_15 | 3026.16 | 3351.43 | 90.29 |
| M_H_DQS_DN_16 | 3127.52 | 3531.92 | 88.55 |
| M_H_DQS_DN_17 | 2044.74 | 2165.4699999999998 | 94.42 |
| M_H_DQS_DP_0 | 2828.39 | 3036.12 | 93.16 |
| M_H_DQS_DP_1 | 2594.0700000000002 | 2718.52 | 95.42 |
| M_H_DQS_DP_2 | 2446.13 | 2613.4 | 93.6 |
| M_H_DQS_DP_3 | 2200.61 | 2285.1999999999998 | 96.3 |
| M_H_DQS_DP_4 | 2057.87 | 1987.35 | 103.55 |
| M_H_DQS_DP_5 | 2166.8000000000002 | 2405.9699999999998 | 90.06 |
| M_H_DQS_DP_6 | 3022.76 | 3214.18 | 94.04 |
| M_H_DQS_DP_7 | 3122.03 | 3378.09 | 92.42 |
| M_H_DQS_DP_8 | 2057.7399999999998 | 2100.08 | 97.98 |
| M_H_DQS_DP_9 | 2829 | 3237.96 | 87.37 |
| M_H_DQS_DP_10 | 2610.83 | 2850.96 | 91.58 |
| M_H_DQS_DP_11 | 2445.0300000000002 | 2735.24 | 89.39 |
| M_H_DQS_DP_12 | 2225.7199999999998 | 2487.04 | 89.49 |
| M_H_DQS_DP_13 | 2056.59 | 2219.4299999999998 | 92.66 |
| M_H_DQS_DP_14 | 2162.58 | 2463.35 | 87.79 |
| M_H_DQS_DP_15 | 3028.16 | 3326.26 | 91.04 |
| M_H_DQS_DP_16 | 3126.17 | 3490.17 | 89.57 |
| M_H_DQS_DP_17 | 2044.31 | 2301.92 | 88.81 |
| M_H_DQ_0 | 2828.15 | 3264.89 | 86.62 |
| M_H_DQ_1 | 2827.4 | 2978.83 | 94.92 |
| M_H_DQ_2 | 2825.06 | 3142.35 | 89.9 |
| M_H_DQ_3 | 2830.5 | 3007.56 | 94.11 |
| M_H_DQ_4 | 2830.89 | 3277.12 | 86.38 |
| M_H_DQ_5 | 2828.39 | 3151.05 | 89.76 |
| M_H_DQ_6 | 2829.53 | 3129.28 | 90.42 |
| M_H_DQ_7 | 2821.81 | 3034.49 | 92.99 |
| M_H_DQ_8 | 2636.04 | 2877.89 | 91.6 |
| M_H_DQ_9 | 2640.44 | 2812.51 | 93.88 |
| M_H_DQ_10 | 2637.56 | 2965.43 | 88.94 |
| M_H_DQ_11 | 2638.94 | 2679.36 | 98.49 |
| M_H_DQ_12 | 2641.03 | 3079.52 | 85.76 |
| M_H_DQ_13 | 2637.59 | 2904.73 | 90.8 |
| M_H_DQ_14 | 2639.15 | 2937.66 | 89.84 |
| M_H_DQ_15 | 2637.77 | 2676.89 | 98.54 |
| M_H_DQ_16 | 2445.84 | 2787.47 | 87.74 |
| M_H_DQ_17 | 2442.04 | 2581.41 | 94.6 |
| M_H_DQ_18 | 2439.9 | 2629.03 | 92.81 |
| M_H_DQ_19 | 2443.65 | 2548.94 | 95.87 |
| M_H_DQ_20 | 2442.89 | 2799.7 | 87.26 |
| M_H_DQ_21 | 2443.25 | 2593.63 | 94.2 |
| M_H_DQ_22 | 2444.92 | 2681.26 | 91.19 |
| M_H_DQ_23 | 2441.9499999999998 | 2601.17 | 93.88 |
| M_H_DQ_24 | 2223.04 | 2484.5700000000002 | 89.47 |
| M_H_DQ_25 | 2223.08 | 2379.1799999999998 | 93.44 |
| M_H_DQ_26 | 2225.2399999999998 | 2452.11 | 90.75 |
| M_H_DQ_27 | 2224.9 | 2220.7399999999998 | 100.19 |
| M_H_DQ_28 | 2227.35 | 2536.8000000000002 | 87.8 |
| M_H_DQ_29 | 2222.31 | 2376.71 | 93.5 |
| M_H_DQ_30 | 2219.08 | 2424.34 | 91.53 |
| M_H_DQ_31 | 2224.94 | 2192.9699999999998 | 101.46 |
| M_H_DQ_32 | 2055.2600000000002 | 2112.5 | 97.29 |
| M_H_DQ_33 | 2056.35 | 1893.36 | 108.61 |
| M_H_DQ_34 | 2061.46 | 2159.66 | 95.45 |
| M_H_DQ_35 | 2058.4699999999998 | 2146.5 | 95.9 |
| M_H_DQ_36 | 2054.38 | 2125.5700000000002 | 96.65 |
| M_H_DQ_37 | 2057.6799999999998 | 1891.73 | 108.77 |
| M_H_DQ_38 | 2057.1999999999998 | 2147.4299999999998 | 95.8 |
| M_H_DQ_39 | 2058.39 | 2228.9699999999998 | 92.35 |
| M_H_DQ_40 | 2181.41 | 2491.12 | 87.57 |
| M_H_DQ_41 | 2181.6999999999998 | 2423.2600000000002 | 90.03 |
| M_H_DQ_42 | 2190.08 | 2649.56 | 82.66 |
| M_H_DQ_43 | 2187.7199999999998 | 2525.12 | 86.64 |
| M_H_DQ_44 | 2182.15 | 2384.19 | 91.53 |
| M_H_DQ_45 | 2183.54 | 2291.0300000000002 | 95.31 |
| M_H_DQ_46 | 2181.0700000000002 | 2597.33 | 83.97 |
| M_H_DQ_47 | 2180.15 | 2512.9 | 86.76 |
| M_H_DQ_48 | 3024.26 | 3204.63 | 94.37 |
| M_H_DQ_49 | 3026.56 | 2956.09 | 102.38 |
| M_H_DQ_50 | 3027.79 | 3455.89 | 87.61 |
| M_H_DQ_51 | 3026.07 | 3472.13 | 87.15 |
| M_H_DQ_52 | 3029.4 | 3207.1 | 94.46 |
| M_H_DQ_53 | 3026.53 | 2918.56 | 103.7 |
| M_H_DQ_54 | 3031.31 | 3348.96 | 90.52 |
| M_H_DQ_55 | 3026.64 | 3266.41 | 92.66 |
| M_H_DQ_56 | 3125.8 | 3313.84 | 94.33 |
| M_H_DQ_57 | 3125.8 | 3245.98 | 96.3 |
| M_H_DQ_58 | 3127.05 | 3745.78 | 83.48 |
| M_H_DQ_59 | 3127.77 | 3606.64 | 86.72 |
| M_H_DQ_60 | 3125.91 | 3261.61 | 95.84 |
| M_H_DQ_61 | 3126.89 | 3263.15 | 95.82 |
| M_H_DQ_62 | 3127.21 | 3609.45 | 86.64 |
| M_H_DQ_63 | 3125.6 | 3514.42 | 88.94 |
| M_H_ECC_0 | 2044.82 | 2314.15 | 88.36 |
| M_H_ECC_1 | 2037.22 | 2028.08 | 100.45 |
| M_H_ECC_2 | 2043.03 | 2155.71 | 94.77 |
| M_H_ECC_3 | 2045.77 | 1995.62 | 102.51 |
| M_H_ECC_4 | 2045.39 | 2326.38 | 87.92 |
| M_H_ECC_5 | 2036.77 | 2120.31 | 96.06 |
| M_H_ECC_6 | 2044.74 | 2207.94 | 92.61 |
| M_H_ECC_7 | 2044.78 | 2047.85 | 99.85 |
| M_H_MA_0 | 2019.89 | 1831.84 | 110.27 |
| M_H_MA_1 | 2022.62 | 1843.17 | 109.74 |
| M_H_MA_2 | 2032.09 | 1613.56 | 125.94 |
| M_H_MA_3 | 2024.45 | 1844.93 | 109.73 |
| M_H_MA_4 | 2015.55 | 1705.79 | 118.16 |
| M_H_MA_5 | 1999.61 | 1787.55 | 111.86 |
| M_H_MA_6 | 2024.59 | 1857.16 | 109.02 |
| M_H_MA_7 | 2009.54 | 1799.78 | 111.65 |
| M_H_MA_8 | 2014.86 | 1812.93 | 111.14 |
| M_H_MA_9 | 2013.75 | 1825.16 | 110.33 |
| M_H_MA_10 | 2017.37 | 1759.75 | 114.64 |
| M_H_MA_11 | 2022.25 | 1755.55 | 115.19 |
| M_H_MA_12 | 1958.01 | 2041.62 | 95.9 |
| M_H_MA_13 | 1941.36 | 1916.32 | 101.31 |
| M_H_MA_14 | 2015.22 | 1742.46 | 115.65 |
| M_H_MA_15 | 2016.29 | 1879 | 107.31 |
| M_H_MA_16 | 2014 | 1839.84 | 109.47 |
| M_H_MA_17 | 1939.2 | 1928.55 | 100.55 |
| M_H_ODT_0 | 1830.61 | 2074.25 | 88.25 |
| M_H_ODT_1 | 1805.63 | 2044.01 | 88.34 |
| M_H_ODT_2 | 1473.71 | 1633.76 | 90.2 |
| M_H_ODT_3 | 1488.32 | 1698.22 | 87.64 |
| M_H_PAR | 2013.86 | 1625.77 | 123.87 |
| NCSI_ARB_IN | 220.28 | 170.96 | 128.85 |
| NCSI_ARB_OUT | 68.2 | 68.73 | 99.23 |
| NGFF_LED_N | 6078.34 | 5377.23 | 113.04 |
| NIC0_CT_POWER | 480.24 | 954.17 | 50.33 |
| NIC0_MDI0_N0 | 276.58 | 301.24 | 91.81 |
| NIC0_MDI0_N1 | 283.76 | 325.12 | 87.28 |
| NIC0_MDI0_N2 | 1631.6 | 1132.8399999999999 | 144.03 |
| NIC0_MDI0_N3 | 1329.91 | 1015.72 | 130.93 |
| NIC0_MDI0_N0_R | 2829.87 | 1507.41 | 187.73 |
| NIC0_MDI0_N1_R | 2533.4299999999998 | 1663.26 | 152.32 |
| NIC0_MDI0_N2_R | 2598.52 | 1461.22 | 177.83 |
| NIC0_MDI0_N3_R | 2495.98 | 1595.06 | 156.47999999999999 |
| NIC0_MDI0_P0 | 276.41000000000003 | 279.93 | 98.74 |
| NIC0_MDI0_P1 | 284.56 | 303.8 | 93.67 |
| NIC0_MDI0_P2 | 1635.48 | 1172.2 | 139.52000000000001 |
| NIC0_MDI0_P3 | 1329.22 | 1054.0999999999999 | 126.1 |
| NIC0_MDI0_P0_R | 2847.79 | 1546.33 | 184.16 |
| NIC0_MDI0_P1_R | 2534.09 | 1587.18 | 159.66 |
| NIC0_MDI0_P2_R | 2598.38 | 1490.3 | 174.35 |
| NIC0_MDI0_P3_R | 2478.73 | 1474.14 | 168.15 |
| NIC1_PCIE_OFF_N | 6178.27 | 5577.07 | 110.78 |
| NIC_JTCK | 122.21 | 139.6 | 87.54 |
| NIC_JTDI | 188.31 | 231.31 | 81.41 |
| NIC_JTDO | 198.02 | 250.75 | 78.97 |
| NIC_JTMS | 125.49 | 147.28 | 85.2 |
| NOA_0_FM_USB_OC_0_N | 994.48 | 871.88 | 114.06 |
| NOA_10_FM_BIOS_ADV_FUNCTIONS | 514.73 | 570.59 | 90.21 |
| NOA_12_FM_NM_THROTTLE_N | 4111.6400000000003 | 3149.68 | 130.54 |
| NOA_13_FM_CPU_PROCHOT_N | 3578.45 | 2833.77 | 126.28 |
| NOA_14_GP18_TP | 858.41 | 673.95 | 127.37 |
| NOA_1_FM_USB_OC_1_N | 878.02 | 680.36 | 129.05000000000001 |
| NOA_2_FM_USB_OC_2_N | 308.25 | 359.44 | 85.76 |
| NOA_3_FM_USB_OC_3_N | 320.23 | 375.36 | 85.31 |
| NOA_5_FM_USB_OC_5_N | 623.25 | 706.75 | 88.19 |
| NOA_6_FM_USB_OC_6_N | 268.54000000000002 | 233.08 | 115.21 |
| NOA_7_FM_USB_OC_7_N | 181.47 | 186.05 | 97.54 |
| NOA_8_GP21_PD | 149.87 | 102.04 | 146.88 |
| NOA_9_RST_PCIE_PCH_N | 5001.21 | 3026.04 | 165.27 |
| NVDIMM_PRSNT | 480.15 | 487.52 | 98.49 |
| NVDIMM_PRSNT_R | 7279.52 | 4602.63 | 158.16 |
| NVM_CS_N | 189.05 | 210.61 | 89.76 |
| NVM_CS_N_R | 480.52 | 384.99 | 124.81 |
| NVM_SI | 270.36 | 233.23 | 115.92 |
| NVM_SI_R | 381.39 | 362 | 105.36 |
| NVM_SK | 111.19 | 135.71 | 81.94 |
| NVM_SK_R | 448.16 | 513.9 | 87.21 |
| NVM_SO | 159.33000000000001 | 190.42 | 83.67 |
| NVM_SO_R | 416.1 | 362.19 | 114.88 |
| NV_SAVE_CHA_DIMM0 | 8529.42 | 7546.88 | 113.02 |
| NV_SAVE_CHA_DIMM1 | 8503.4699999999993 | 7756.6 | 109.63 |
| NV_SAVE_CHB_DIMM0 | 7982.89 | 7759.6 | 102.88 |
| NV_SAVE_CHB_DIMM1 | 9081.4699999999993 | 8429.74 | 107.73 |
| NV_SAVE_CHC_DIMM0 | 11821.14 | 11644.69 | 101.52 |
| NV_SAVE_CHC_DIMM1 | 11657.02 | 11372.62 | 102.5 |
| NV_SAVE_CHD_DIMM0 | 12283.03 | 10769.09 | 114.06 |
| NV_SAVE_CHD_DIMM1 | 10490.3 | 10571.77 | 99.23 |
| NV_SAVE_CHE_DIMM0 | 19786.939999999999 | 18081.78 | 109.43 |
| NV_SAVE_CHE_DIMM1 | 19968.45 | 17607.73 | 113.41 |
| NV_SAVE_CHF_DIMM0 | 20732.87 | 17800.400000000001 | 116.47 |
| NV_SAVE_CHF_DIMM1 | 18725.64 | 16824.82 | 111.3 |
| NV_SAVE_CHG_DIMM0 | 15516.23 | 14452.56 | 107.36 |
| NV_SAVE_CHG_DIMM1 | 15175.2 | 14189.12 | 106.95 |
| NV_SAVE_CHH_DIMM0 | 16906.55 | 14626.08 | 115.59 |
| NV_SAVE_CHH_DIMM1 | 16142.9 | 14848.94 | 108.71 |
| OSC2_AS_CLKIN | 225.93 | 201.51 | 112.12 |
| OSC2_CONT | 261.05 | 138.86000000000001 | 187.99 |
| OSC2_OUT | 253.91 | 157.86000000000001 | 160.85 |
| P0V7_CPU0_ERRS_VREF | 313.08999999999997 | 231.69 | 135.13 |
| P0V7_CPU1_ERRS_VREF | 415.63 | 433.14 | 95.96 |
| P0V7_GTL_VREF_0 | 301.62 | 179.5 | 168.04 |
| P0V7_GTL_VREF_1 | 259.61 | 313.5 | 82.81 |
| P0V7_GTL_VREF_2 | 210.99 | 231.18 | 91.27 |
| P0V9_I210 | 2098.6 | 1618.09 | 129.69999999999999 |
| P12V_FAN | 77.3 | 647.38 | 11.94 |
| P12V_FAN1 | 924.44 | 4095.56 | 22.57 |
| P12V_HDD | 228.08 | 1362.49 | 16.739999999999998 |
| P12V_HDD_HDPR1 | 124.56 | 252.23 | 49.38 |
| P12V_MAIN | 3968.29 | 5496.8 | 72.19 |
| P12V_PCIE_HDD | 2802.07 | 11403.94 | 24.57 |
| P12V_PG | 421.19 | 436.14 | 96.57 |
| P12V_SENSE_OUT | 642.78 | 462.46 | 138.99 |
| P12V_SENSE_OUT_CMP | 295.69 | 216.98 | 136.27000000000001 |
| P12V_STBY | 14145.16 | 56728.88 | 24.93 |
| P1V05_DMI_PLL | 0 | 269 | 0 |
| P1V05_DSW_INT_CAP | 215.07 | 244.17 | 88.08 |
| P1V05_DSW_INT_CAP_R | 79.73 | 83.36 | 95.64 |
| P1V05_ME_PWR_OPTION | 739.36 | 2221.5500000000002 | 33.28 |
| P1V05_PCH | 1897.59 | 7848.79 | 24.18 |
| P1V05_PCH_EN | 457.41 | 352.19 | 129.88 |
| P1V05_PCH_LL | 203.91 | 372.32 | 54.77 |
| P1V05_PCH_LL_R | 193.26 | 187.93 | 102.83 |
| P1V05_PCH_MODE | 376.22 | 286.01 | 131.54 |
| P1V05_PCH_REOMTEN | 2374.35 | 1326 | 179.06 |
| P1V05_PCH_REOMTEP | 2394.5100000000002 | 1240.5 | 193.03 |
| P1V05_PCH_RF | 191.97 | 181.64 | 105.69 |
| P1V05_PCH_ROVP | 157.72 | 120.24 | 131.16999999999999 |
| P1V05_PCH_SNB | 50.9 | 77 | 66.099999999999994 |
| P1V05_PCH_TRIP | 96.46 | 24.81 | 388.8 |
| P1V05_PCH_VBST | 184.71 | 162.94 | 113.36 |
| P1V05_PCH_VBST_RC | 56.21 | 65 | 86.48 |
| P1V05_PCH_VDD | 238.27 | 273.2 | 87.21 |
| P1V05_PCH_VFB | 167.76 | 165.5 | 101.37 |
| P1V05_PCH_VFB_R | 56.46 | 75.5 | 74.78 |
| P1V05_PCH_VIN | 0 | 313.17 | 0 |
| P1V05_PCH_VREG | 197.53 | 172.88 | 114.26 |
| P1V05_SATA3X_PLL | 312.77 | 366.96 | 85.23 |
| P1V05_SATA3_PLL | 46.59 | 245 | 19.02 |
| P1V05_STBY_PCH | 5654.34 | 6681.12 | 84.63 |
| P1V05_STBY_PCH_CC | 923.86 | 813.86 | 113.52 |
| P1V05_STBY_PCH_CC_R | 273.08999999999997 | 147.71 | 184.89 |
| P1V05_STBY_PCH_EN_R | 200.51 | 165.07 | 121.47 |
| P1V05_STBY_PCH_SS | 102.37 | 117.07 | 87.45 |
| P1V05_STBY_PCH_SW | 176.41 | 630.19000000000005 | 27.99 |
| P1V05_STBY_PCH_VBST | 163.68 | 210.46 | 77.77 |
| P1V05_STBY_PCH_VBST_RR | 111.36 | 86.01 | 129.47 |
| P1V05_STBY_PCH_VCC | 304.36 | 257.82 | 118.05 |
| P1V05_STBY_PCH_VFB | 223.68 | 219.53 | 101.89 |
| P1V05_STBY_PCH_VFB_R | 795 | 730.07 | 108.89 |
| P1V05_STBY_PCH_VIN | 0 | 392.5 | 0 |
| P1V05_STBY_PCH_VO | 184.74 | 144 | 128.29 |
| P1V05_STBY_PCH_VRG5 | 220.11 | 140 | 157.22 |
| P1V05_STBY_PCH__SNB | 63.8 | 67.739999999999995 | 94.18 |
| P1V05_SUS_INT_CAP | 80.92 | 42.41 | 190.82 |
| P1V05_USB3_PLL | 0 | 306.5 | 0 |
| P1V05_VCCRTCEXT | 72.72 | 38.200000000000003 | 190.36 |
| P1V05_XCK_DCB | 278.02999999999997 | 341 | 81.53 |
| P1V05_XCK_VRM | 411.5 | 475.79 | 86.49 |
| P1V05_XCK_VRM_L | 0 | 130.5 | 0 |
| P1V26_STBY | 2509.02 | 5906.85 | 42.48 |
| P1V538_STBY | 3157.51 | 7566.3 | 41.73 |
| P1V5_I210 | 646.66999999999996 | 795.64 | 81.28 |
| P1V5_PCH | 2653.73 | 4117.74 | 64.45 |
| P1V5_VCCSST_INT_CAP | 275.3 | 298.54000000000002 | 92.22 |
| P1V8_STBY | 2995.51 | 6242.62 | 47.98 |
| P1V8_STBY_BMC_CC | 867.7 | 555.87 | 156.1 |
| P1V8_STBY_BMC_CC_R | 408.3 | 406.12 | 100.54 |
| P1V8_STBY_BMC_EN_R | 149.66999999999999 | 145.47 | 102.89 |
| P1V8_STBY_BMC_SS | 104.44 | 126.25 | 82.73 |
| P1V8_STBY_BMC_SW | 210.53 | 518.57000000000005 | 40.6 |
| P1V8_STBY_BMC_VBST | 0 | 102.79 | 0 |
| P1V8_STBY_BMC_VBST_RR | 47.81 | 52.5 | 91.07 |
| P1V8_STBY_BMC_VCC | 156.41 | 181.9 | 85.99 |
| P1V8_STBY_BMC_VFB | 296.70999999999998 | 346.05 | 85.74 |
| P1V8_STBY_BMC_VFB_R | 772.61 | 649.5 | 118.95 |
| P1V8_STBY_BMC_VIN | 63.68 | 411.42 | 15.48 |
| P1V8_STBY_BMC_VO | 110.67 | 32.15 | 344.24 |
| P1V8_STBY_BMC_VRG5 | 200.38 | 226.1 | 88.63 |
| P1V8_STBY_BMC__SNB | 0 | 92.53 | 0 |
| P2E_WBG_BMC_RX_C_DN8 | 4926.46 | 4993.3500000000004 | 98.66 |
| P2E_WBG_BMC_RX_C_DP8 | 4930.9799999999996 | 4997.82 | 98.66 |
| P2E_WBG_BMC_RX_DN8 | 368.94 | 492.48 | 74.92 |
| P2E_WBG_BMC_RX_DP8 | 367 | 426.51 | 86.05 |
| P2E_WBG_BMC_TX_C_DN_8 | 5936.21 | 5813.08 | 102.12 |
| P2E_WBG_BMC_TX_C_DP_8 | 5933.9 | 5878.59 | 100.94 |
| P2E_WBG_BMC_TX_DN_8 | 192.48 | 153.59 | 125.32 |
| P2E_WBG_BMC_TX_DP_8 | 195.4 | 210.48 | 92.84 |
| P2E_WBG_LAN_RX_C_DN_5 | 5928.73 | 5283.71 | 112.21 |
| P2E_WBG_LAN_RX_C_DP_5 | 5931.23 | 5349.71 | 110.87 |
| P2E_WBG_LAN_RX_DN_5 | 169.07 | 161.91 | 104.42 |
| P2E_WBG_LAN_RX_DP_5 | 168.24 | 178.23 | 94.39 |
| P2E_WBG_LAN_TX_C_DN_5 | 173.84 | 176.46 | 98.52 |
| P2E_WBG_LAN_TX_C_DP_5 | 174.07 | 191.31 | 90.99 |
| P2E_WBG_LAN_TX_DN_5 | 6827.15 | 6360.72 | 107.33 |
| P2E_WBG_LAN_TX_DP_5 | 6826.97 | 6356.26 | 107.41 |
| P2E_WBG_NGFF_RX_C_DN_1 | 4697.17 | 4986.32 | 94.2 |
| P2E_WBG_NGFF_RX_C_DN_2 | 5101.28 | 4398.74 | 115.97 |
| P2E_WBG_NGFF_RX_C_DN_3 | 5394.97 | 5070.8100000000004 | 106.39 |
| P2E_WBG_NGFF_RX_C_DN_4 | 5392.43 | 4650.96 | 115.94 |
| P2E_WBG_NGFF_RX_C_DP_1 | 4696.6499999999996 | 5042.16 | 93.15 |
| P2E_WBG_NGFF_RX_C_DP_2 | 5103.3599999999997 | 4349.0600000000004 | 117.34 |
| P2E_WBG_NGFF_RX_C_DP_3 | 5394.29 | 5035.29 | 107.13 |
| P2E_WBG_NGFF_RX_C_DP_4 | 5390.62 | 4661.28 | 115.65 |
| P2E_WBG_NGFF_TX_C_DN_1 | 565.77 | 361.05 | 156.69999999999999 |
| P2E_WBG_NGFF_TX_C_DN_2 | 86.36 | 86.91 | 99.37 |
| P2E_WBG_NGFF_TX_C_DN_3 | 78.58 | 80.2 | 97.98 |
| P2E_WBG_NGFF_TX_C_DN_4 | 80.55 | 81.2 | 99.2 |
| P2E_WBG_NGFF_TX_C_DP_1 | 564.34 | 340.54 | 165.72 |
| P2E_WBG_NGFF_TX_C_DP_2 | 86.38 | 87.36 | 98.88 |
| P2E_WBG_NGFF_TX_C_DP_3 | 77.61 | 77.510000000000005 | 100.12 |
| P2E_WBG_NGFF_TX_C_DP_4 | 80.69 | 81.569999999999993 | 98.93 |
| P2E_WBG_NGFF_TX_DN_1 | 5207.09 | 5653.48 | 92.1 |
| P2E_WBG_NGFF_TX_DN_2 | 4782.8599999999997 | 5414.49 | 88.33 |
| P2E_WBG_NGFF_TX_DN_3 | 4997.49 | 5411.71 | 92.35 |
| P2E_WBG_NGFF_TX_DN_4 | 5224.38 | 5239.66 | 99.71 |
| P2E_WBG_NGFF_TX_DP_1 | 5209.37 | 5632.28 | 92.49 |
| P2E_WBG_NGFF_TX_DP_2 | 4783.1499999999996 | 5327.31 | 89.79 |
| P2E_WBG_NGFF_TX_DP_3 | 4999.1499999999996 | 5336.45 | 93.68 |
| P2E_WBG_NGFF_TX_DP_4 | 5225.62 | 5164.66 | 101.18 |
| P2V5_REF | 1211.75 | 1485.32 | 81.58 |
| P3E_CPU0_PE1_RISER1_RX_DN_0 | 11021.78 | 11312.28 | 97.43 |
| P3E_CPU0_PE1_RISER1_RX_DN_1 | 10880.7 | 11355.29 | 95.82 |
| P3E_CPU0_PE1_RISER1_RX_DN_2 | 10785.77 | 11227.85 | 96.06 |
| P3E_CPU0_PE1_RISER1_RX_DN_3 | 10708.31 | 11165.31 | 95.91 |
| P3E_CPU0_PE1_RISER1_RX_DN_4 | 10471.459999999999 | 10887.23 | 96.18 |
| P3E_CPU0_PE1_RISER1_RX_DN_5 | 10482.459999999999 | 10773.15 | 97.3 |
| P3E_CPU0_PE1_RISER1_RX_DN_6 | 10341.870000000001 | 10629.12 | 97.3 |
| P3E_CPU0_PE1_RISER1_RX_DN_7 | 10442.94 | 10456.94 | 99.87 |
| P3E_CPU0_PE1_RISER1_RX_DP_0 | 11024.36 | 11450.39 | 96.28 |
| P3E_CPU0_PE1_RISER1_RX_DP_1 | 10881.47 | 11375.92 | 95.65 |
| P3E_CPU0_PE1_RISER1_RX_DP_2 | 10787.36 | 11248.48 | 95.9 |
| P3E_CPU0_PE1_RISER1_RX_DP_3 | 10709.1 | 11185.94 | 95.74 |
| P3E_CPU0_PE1_RISER1_RX_DP_4 | 10471.700000000001 | 10867.86 | 96.35 |
| P3E_CPU0_PE1_RISER1_RX_DP_5 | 10486.01 | 10787.94 | 97.2 |
| P3E_CPU0_PE1_RISER1_RX_DP_6 | 10338.98 | 10629.75 | 97.26 |
| P3E_CPU0_PE1_RISER1_RX_DP_7 | 10444.85 | 10457.57 | 99.88 |
| P3E_CPU0_PE1_RISER1_TX_C_DN_0 | 199.54 | 206.22 | 96.76 |
| P3E_CPU0_PE1_RISER1_TX_C_DN_1 | 207.83 | 131.16999999999999 | 158.44 |
| P3E_CPU0_PE1_RISER1_TX_C_DN_2 | 423.96 | 355.47 | 119.27 |
| P3E_CPU0_PE1_RISER1_TX_C_DN_3 | 353.64 | 275.99 | 128.13999999999999 |
| P3E_CPU0_PE1_RISER1_TX_C_DN_4 | 234.73 | 156.34 | 150.13999999999999 |
| P3E_CPU0_PE1_RISER1_TX_C_DN_5 | 219.92 | 150.30000000000001 | 146.32 |
| P3E_CPU0_PE1_RISER1_TX_C_DN_6 | 218.16 | 144.57 | 150.9 |
| P3E_CPU0_PE1_RISER1_TX_C_DN_7 | 217.1 | 150.54 | 144.21 |
| P3E_CPU0_PE1_RISER1_TX_C_DP_0 | 199.7 | 130.49 | 153.04 |
| P3E_CPU0_PE1_RISER1_TX_C_DP_1 | 208.33 | 206.54 | 100.87 |
| P3E_CPU0_PE1_RISER1_TX_C_DP_2 | 422.22 | 437.58 | 96.49 |
| P3E_CPU0_PE1_RISER1_TX_C_DP_3 | 354.03 | 357.1 | 99.14 |
| P3E_CPU0_PE1_RISER1_TX_C_DP_4 | 233.39 | 237.92 | 98.1 |
| P3E_CPU0_PE1_RISER1_TX_C_DP_5 | 220.15 | 225.56 | 97.6 |
| P3E_CPU0_PE1_RISER1_TX_C_DP_6 | 218.63 | 220.7 | 99.06 |
| P3E_CPU0_PE1_RISER1_TX_C_DP_7 | 215.63 | 226.7 | 95.12 |
| P3E_CPU0_PE1_RISER1_TX_DN_0 | 10946.95 | 10811.98 | 101.25 |
| P3E_CPU0_PE1_RISER1_TX_DN_1 | 10905.66 | 10695.36 | 101.97 |
| P3E_CPU0_PE1_RISER1_TX_DN_2 | 10440.09 | 10299.06 | 101.37 |
| P3E_CPU0_PE1_RISER1_TX_DN_3 | 10091.82 | 10275.76 | 98.21 |
| P3E_CPU0_PE1_RISER1_TX_DN_4 | 9776.32 | 10180.59 | 96.03 |
| P3E_CPU0_PE1_RISER1_TX_DN_5 | 9710.91 | 10119.23 | 95.96 |
| P3E_CPU0_PE1_RISER1_TX_DN_6 | 9559.98 | 9978.7999999999993 | 95.8 |
| P3E_CPU0_PE1_RISER1_TX_DN_7 | 9544.5499999999993 | 9901.6200000000008 | 96.39 |
| P3E_CPU0_PE1_RISER1_TX_DP_0 | 10948.13 | 10888.34 | 100.55 |
| P3E_CPU0_PE1_RISER1_TX_DP_1 | 10902.37 | 10771.36 | 101.22 |
| P3E_CPU0_PE1_RISER1_TX_DP_2 | 10438.68 | 10375.06 | 100.61 |
| P3E_CPU0_PE1_RISER1_TX_DP_3 | 10093.91 | 10352.76 | 97.5 |
| P3E_CPU0_PE1_RISER1_TX_DP_4 | 9773.7199999999993 | 10250.42 | 95.35 |
| P3E_CPU0_PE1_RISER1_TX_DP_5 | 9706.18 | 10192.16 | 95.23 |
| P3E_CPU0_PE1_RISER1_TX_DP_6 | 9560.02 | 10047.56 | 95.15 |
| P3E_CPU0_PE1_RISER1_TX_DP_7 | 9542.68 | 9958.61 | 95.82 |
| P3E_CPU0_PE2_RISER1_RX_DN_0 | 10758.23 | 10755.97 | 100.02 |
| P3E_CPU0_PE2_RISER1_RX_DN_1 | 10854.15 | 10670.61 | 101.72 |
| P3E_CPU0_PE2_RISER1_RX_DN_2 | 10749.32 | 10356.469999999999 | 103.79 |
| P3E_CPU0_PE2_RISER1_RX_DN_3 | 10828.8 | 10265.15 | 105.49 |
| P3E_CPU0_PE2_RISER1_RX_DN_4 | 10871.86 | 10244.27 | 106.13 |
| P3E_CPU0_PE2_RISER1_RX_DN_5 | 10825.45 | 10030.030000000001 | 107.93 |
| P3E_CPU0_PE2_RISER1_RX_DN_6 | 10874.12 | 9954.1299999999992 | 109.24 |
| P3E_CPU0_PE2_RISER1_RX_DN_7 | 10742.17 | 9760.2099999999991 | 110.06 |
| P3E_CPU0_PE2_RISER1_RX_DN_8 | 10829.83 | 9773.2199999999993 | 110.81 |
| P3E_CPU0_PE2_RISER1_RX_DN_9 | 10739.76 | 9596.66 | 111.91 |
| P3E_CPU0_PE2_RISER1_RX_DN_10 | 10802.39 | 9575.3799999999992 | 112.81 |
| P3E_CPU0_PE2_RISER1_RX_DN_11 | 10671.6 | 9419.4 | 113.29 |
| P3E_CPU0_PE2_RISER1_RX_DN_12 | 10934.62 | 9234.1 | 118.42 |
| P3E_CPU0_PE2_RISER1_RX_DN_13 | 11193.98 | 9251.56 | 121 |
| P3E_CPU0_PE2_RISER1_RX_DN_14 | 10827.93 | 8999.2000000000007 | 120.32 |
| P3E_CPU0_PE2_RISER1_RX_DN_15 | 10879.79 | 9002.44 | 120.85 |
| P3E_CPU0_PE2_RISER1_RX_DP_0 | 10759.68 | 10914.08 | 98.59 |
| P3E_CPU0_PE2_RISER1_RX_DP_1 | 10853.67 | 10828.72 | 100.23 |
| P3E_CPU0_PE2_RISER1_RX_DP_2 | 10749.06 | 10514.58 | 102.23 |
| P3E_CPU0_PE2_RISER1_RX_DP_3 | 10825.84 | 10423.26 | 103.86 |
| P3E_CPU0_PE2_RISER1_RX_DP_4 | 10872.57 | 10402.379999999999 | 104.52 |
| P3E_CPU0_PE2_RISER1_RX_DP_5 | 10827 | 10188.14 | 106.27 |
| P3E_CPU0_PE2_RISER1_RX_DP_6 | 10872.97 | 10112.24 | 107.52 |
| P3E_CPU0_PE2_RISER1_RX_DP_7 | 10744.43 | 9863.6200000000008 | 108.93 |
| P3E_CPU0_PE2_RISER1_RX_DP_8 | 10833.16 | 9773.85 | 110.84 |
| P3E_CPU0_PE2_RISER1_RX_DP_9 | 10737.11 | 9597.2900000000009 | 111.88 |
| P3E_CPU0_PE2_RISER1_RX_DP_10 | 10801.78 | 9516.01 | 113.51 |
| P3E_CPU0_PE2_RISER1_RX_DP_11 | 10668.28 | 9420.0300000000007 | 113.25 |
| P3E_CPU0_PE2_RISER1_RX_DP_12 | 10934.83 | 9234.73 | 118.41 |
| P3E_CPU0_PE2_RISER1_RX_DP_13 | 11193.76 | 9192.19 | 121.77 |
| P3E_CPU0_PE2_RISER1_RX_DP_14 | 10830.55 | 9010.77 | 120.2 |
| P3E_CPU0_PE2_RISER1_RX_DP_15 | 10880.45 | 8943.07 | 121.66 |
| P3E_CPU0_PE2_RISER1_TX_C_DN_0 | 268.52999999999997 | 256.62 | 104.64 |
| P3E_CPU0_PE2_RISER1_TX_C_DN_1 | 252.65 | 292.62 | 86.34 |
| P3E_CPU0_PE2_RISER1_TX_C_DN_2 | 252.77 | 292.62 | 86.38 |
| P3E_CPU0_PE2_RISER1_TX_C_DN_3 | 252.77 | 292.62 | 86.38 |
| P3E_CPU0_PE2_RISER1_TX_C_DN_4 | 252.77 | 292.62 | 86.38 |
| P3E_CPU0_PE2_RISER1_TX_C_DN_5 | 252.77 | 292.62 | 86.38 |
| P3E_CPU0_PE2_RISER1_TX_C_DN_6 | 252.77 | 292.62 | 86.38 |
| P3E_CPU0_PE2_RISER1_TX_C_DN_7 | 252.77 | 292.62 | 86.38 |
| P3E_CPU0_PE2_RISER1_TX_C_DN_8 | 313.33999999999997 | 174.51 | 179.55 |
| P3E_CPU0_PE2_RISER1_TX_C_DN_9 | 316.13 | 174.51 | 181.15 |
| P3E_CPU0_PE2_RISER1_TX_C_DN_10 | 313.55 | 174.51 | 179.67 |
| P3E_CPU0_PE2_RISER1_TX_C_DN_11 | 325.07 | 174.51 | 186.27 |
| P3E_CPU0_PE2_RISER1_TX_C_DN_12 | 318.8 | 174.51 | 182.69 |
| P3E_CPU0_PE2_RISER1_TX_C_DN_13 | 313.62 | 173.86 | 180.39 |
| P3E_CPU0_PE2_RISER1_TX_C_DN_14 | 290.05 | 168.37 | 172.27 |
| P3E_CPU0_PE2_RISER1_TX_C_DN_15 | 346.81 | 208.51 | 166.33 |
| P3E_CPU0_PE2_RISER1_TX_C_DP_0 | 268.56 | 174.51 | 153.88999999999999 |
| P3E_CPU0_PE2_RISER1_TX_C_DP_1 | 253.94 | 138.51 | 183.34 |
| P3E_CPU0_PE2_RISER1_TX_C_DP_2 | 254.03 | 138.51 | 183.4 |
| P3E_CPU0_PE2_RISER1_TX_C_DP_3 | 253.94 | 138.51 | 183.34 |
| P3E_CPU0_PE2_RISER1_TX_C_DP_4 | 253.94 | 138.51 | 183.34 |
| P3E_CPU0_PE2_RISER1_TX_C_DP_5 | 253.94 | 138.51 | 183.34 |
| P3E_CPU0_PE2_RISER1_TX_C_DP_6 | 253.94 | 138.51 | 183.34 |
| P3E_CPU0_PE2_RISER1_TX_C_DP_7 | 253.94 | 138.51 | 183.34 |
| P3E_CPU0_PE2_RISER1_TX_C_DP_8 | 312.41000000000003 | 212.74 | 146.85 |
| P3E_CPU0_PE2_RISER1_TX_C_DP_9 | 317.42 | 212.74 | 149.19999999999999 |
| P3E_CPU0_PE2_RISER1_TX_C_DP_10 | 314.73 | 212.74 | 147.94 |
| P3E_CPU0_PE2_RISER1_TX_C_DP_11 | 325.89 | 212.74 | 153.19 |
| P3E_CPU0_PE2_RISER1_TX_C_DP_12 | 320.87 | 212.74 | 150.83000000000001 |
| P3E_CPU0_PE2_RISER1_TX_C_DP_13 | 315.08 | 209.89 | 150.11000000000001 |
| P3E_CPU0_PE2_RISER1_TX_C_DP_14 | 288.32 | 212.74 | 135.52000000000001 |
| P3E_CPU0_PE2_RISER1_TX_C_DP_15 | 344.31 | 211.88 | 162.5 |
| P3E_CPU0_PE2_RISER1_TX_DN_0 | 10550.18 | 10766.91 | 97.99 |
| P3E_CPU0_PE2_RISER1_TX_DN_1 | 10422.43 | 10668.29 | 97.7 |
| P3E_CPU0_PE2_RISER1_TX_DN_2 | 10251.459999999999 | 10531.95 | 97.34 |
| P3E_CPU0_PE2_RISER1_TX_DN_3 | 10036.32 | 10246.31 | 97.95 |
| P3E_CPU0_PE2_RISER1_TX_DN_4 | 9944.8700000000008 | 9990.1299999999992 | 99.55 |
| P3E_CPU0_PE2_RISER1_TX_DN_5 | 9779.2900000000009 | 9831.89 | 99.46 |
| P3E_CPU0_PE2_RISER1_TX_DN_6 | 9998.32 | 9897.19 | 101.02 |
| P3E_CPU0_PE2_RISER1_TX_DN_7 | 9805.31 | 9794.69 | 100.11 |
| P3E_CPU0_PE2_RISER1_TX_DN_8 | 9642.02 | 9714.89 | 99.25 |
| P3E_CPU0_PE2_RISER1_TX_DN_9 | 9610.2900000000009 | 9462.67 | 101.56 |
| P3E_CPU0_PE2_RISER1_TX_DN_10 | 9514.51 | 9351.83 | 101.74 |
| P3E_CPU0_PE2_RISER1_TX_DN_11 | 9641.61 | 9341.0499999999993 | 103.22 |
| P3E_CPU0_PE2_RISER1_TX_DN_12 | 9708.8700000000008 | 9252.9699999999993 | 104.93 |
| P3E_CPU0_PE2_RISER1_TX_DN_13 | 9835.18 | 9162.74 | 107.34 |
| P3E_CPU0_PE2_RISER1_TX_DN_14 | 9696.81 | 9099.6299999999992 | 106.56 |
| P3E_CPU0_PE2_RISER1_TX_DN_15 | 9698.77 | 9069.19 | 106.94 |
| P3E_CPU0_PE2_RISER1_TX_DP_0 | 10551.21 | 10842.91 | 97.31 |
| P3E_CPU0_PE2_RISER1_TX_DP_1 | 10424.09 | 10686.45 | 97.54 |
| P3E_CPU0_PE2_RISER1_TX_DP_2 | 10249.56 | 10550.11 | 97.15 |
| P3E_CPU0_PE2_RISER1_TX_DP_3 | 10036.02 | 10250.31 | 97.91 |
| P3E_CPU0_PE2_RISER1_TX_DP_4 | 9941.1 | 9994.1299999999992 | 99.47 |
| P3E_CPU0_PE2_RISER1_TX_DP_5 | 9777 | 9835.89 | 99.4 |
| P3E_CPU0_PE2_RISER1_TX_DP_6 | 9997.0300000000007 | 9901.19 | 100.97 |
| P3E_CPU0_PE2_RISER1_TX_DP_7 | 9807.2099999999991 | 9798.69 | 100.09 |
| P3E_CPU0_PE2_RISER1_TX_DP_8 | 9640.0400000000009 | 9718.89 | 99.19 |
| P3E_CPU0_PE2_RISER1_TX_DP_9 | 9612.2900000000009 | 9486.67 | 101.32 |
| P3E_CPU0_PE2_RISER1_TX_DP_10 | 9515.2900000000009 | 9375.83 | 101.49 |
| P3E_CPU0_PE2_RISER1_TX_DP_11 | 9644.6200000000008 | 9359.2099999999991 | 103.05 |
| P3E_CPU0_PE2_RISER1_TX_DP_12 | 9711.64 | 9256.9699999999993 | 104.91 |
| P3E_CPU0_PE2_RISER1_TX_DP_13 | 9833.4500000000007 | 9166.74 | 107.27 |
| P3E_CPU0_PE2_RISER1_TX_DP_14 | 9696.1299999999992 | 9043.6299999999992 | 107.22 |
| P3E_CPU0_PE2_RISER1_TX_DP_15 | 9701.09 | 9013.19 | 107.63 |
| P3E_CPU0_PE3_MEZZ_RX_DN_8 | 13357.99 | 12433.1 | 107.44 |
| P3E_CPU0_PE3_MEZZ_RX_DN_9 | 12867.1 | 12174.14 | 105.69 |
| P3E_CPU0_PE3_MEZZ_RX_DN_10 | 12140.04 | 12045.55 | 100.78 |
| P3E_CPU0_PE3_MEZZ_RX_DN_11 | 11995.04 | 11902.89 | 100.77 |
| P3E_CPU0_PE3_MEZZ_RX_DN_12 | 11772.31 | 11835.58 | 99.47 |
| P3E_CPU0_PE3_MEZZ_RX_DN_13 | 11449.46 | 11592.64 | 98.76 |
| P3E_CPU0_PE3_MEZZ_RX_DN_14 | 11338.61 | 11515.4 | 98.46 |
| P3E_CPU0_PE3_MEZZ_RX_DN_15 | 11190.33 | 11393.19 | 98.22 |
| P3E_CPU0_PE3_MEZZ_RX_DP_8 | 13360.04 | 12438.76 | 107.41 |
| P3E_CPU0_PE3_MEZZ_RX_DP_9 | 12868.82 | 12179.79 | 105.66 |
| P3E_CPU0_PE3_MEZZ_RX_DP_10 | 12140.99 | 12051.21 | 100.74 |
| P3E_CPU0_PE3_MEZZ_RX_DP_11 | 11996.56 | 11908.53 | 100.74 |
| P3E_CPU0_PE3_MEZZ_RX_DP_12 | 11772.12 | 11841.24 | 99.42 |
| P3E_CPU0_PE3_MEZZ_RX_DP_13 | 11451.94 | 11599.7 | 98.73 |
| P3E_CPU0_PE3_MEZZ_RX_DP_14 | 11337.23 | 11521.03 | 98.4 |
| P3E_CPU0_PE3_MEZZ_RX_DP_15 | 11190.55 | 11398.83 | 98.17 |
| P3E_CPU0_PE3_MEZZ_TX_C_DN_8 | 167.6 | 138.09 | 121.37 |
| P3E_CPU0_PE3_MEZZ_TX_C_DN_9 | 166.77 | 138.09 | 120.77 |
| P3E_CPU0_PE3_MEZZ_TX_C_DN_10 | 167.6 | 138.1 | 121.36 |
| P3E_CPU0_PE3_MEZZ_TX_C_DN_11 | 167.6 | 138.09 | 121.37 |
| P3E_CPU0_PE3_MEZZ_TX_C_DN_12 | 167.6 | 138.1 | 121.36 |
| P3E_CPU0_PE3_MEZZ_TX_C_DN_13 | 167.6 | 138.09 | 121.37 |
| P3E_CPU0_PE3_MEZZ_TX_C_DN_14 | 167.65 | 138.1 | 121.4 |
| P3E_CPU0_PE3_MEZZ_TX_C_DN_15 | 166.99 | 138.59 | 120.49 |
| P3E_CPU0_PE3_MEZZ_TX_C_DP_8 | 167.27 | 137.33000000000001 | 121.8 |
| P3E_CPU0_PE3_MEZZ_TX_C_DP_9 | 166.57 | 137.33000000000001 | 121.29 |
| P3E_CPU0_PE3_MEZZ_TX_C_DP_10 | 167.26 | 137.33000000000001 | 121.79 |
| P3E_CPU0_PE3_MEZZ_TX_C_DP_11 | 167.27 | 137.33000000000001 | 121.8 |
| P3E_CPU0_PE3_MEZZ_TX_C_DP_12 | 167.26 | 137.33000000000001 | 121.79 |
| P3E_CPU0_PE3_MEZZ_TX_C_DP_13 | 167.27 | 137.33000000000001 | 121.8 |
| P3E_CPU0_PE3_MEZZ_TX_C_DP_14 | 167.21 | 137.33000000000001 | 121.76 |
| P3E_CPU0_PE3_MEZZ_TX_C_DP_15 | 167.87 | 136.83000000000001 | 122.69 |
| P3E_CPU0_PE3_MEZZ_TX_DN_8 | 13513.35 | 11577.66 | 116.72 |
| P3E_CPU0_PE3_MEZZ_TX_DN_9 | 13178.91 | 11457.4 | 115.03 |
| P3E_CPU0_PE3_MEZZ_TX_DN_10 | 12743.67 | 11274.87 | 113.03 |
| P3E_CPU0_PE3_MEZZ_TX_DN_11 | 12535.15 | 11142.47 | 112.5 |
| P3E_CPU0_PE3_MEZZ_TX_DN_12 | 12272.4 | 11552.08 | 106.24 |
| P3E_CPU0_PE3_MEZZ_TX_DN_13 | 11850.8 | 10527.96 | 112.56 |
| P3E_CPU0_PE3_MEZZ_TX_DN_14 | 11754.74 | 10150.790000000001 | 115.8 |
| P3E_CPU0_PE3_MEZZ_TX_DN_15 | 11548.56 | 9923.1299999999992 | 116.38 |
| P3E_CPU0_PE3_MEZZ_TX_DP_8 | 13513.34 | 11578.66 | 116.71 |
| P3E_CPU0_PE3_MEZZ_TX_DP_9 | 13177.91 | 11441.04 | 115.18 |
| P3E_CPU0_PE3_MEZZ_TX_DP_10 | 12746.16 | 11293.21 | 112.87 |
| P3E_CPU0_PE3_MEZZ_TX_DP_11 | 12538.17 | 11157.21 | 112.38 |
| P3E_CPU0_PE3_MEZZ_TX_DP_12 | 12273.08 | 11552.52 | 106.24 |
| P3E_CPU0_PE3_MEZZ_TX_DP_13 | 11854.05 | 10548.96 | 112.37 |
| P3E_CPU0_PE3_MEZZ_TX_DP_14 | 11755.34 | 10211.790000000001 | 115.12 |
| P3E_CPU0_PE3_MEZZ_TX_DP_15 | 11546.92 | 10004.129999999999 | 115.42 |
| P3E_CPU0_PE3_RISER2_RX_DN_0 | 9918.56 | 10282.18 | 96.46 |
| P3E_CPU0_PE3_RISER2_RX_DN_1 | 9480.7199999999993 | 9977.98 | 95.02 |
| P3E_CPU0_PE3_RISER2_RX_DN_2 | 9340.6200000000008 | 9632.93 | 96.97 |
| P3E_CPU0_PE3_RISER2_RX_DN_3 | 9626.18 | 9909.7999999999993 | 97.14 |
| P3E_CPU0_PE3_RISER2_RX_DN_4 | 9450.51 | 9650.48 | 97.93 |
| P3E_CPU0_PE3_RISER2_RX_DN_5 | 8997.43 | 9363.8700000000008 | 96.09 |
| P3E_CPU0_PE3_RISER2_RX_DN_6 | 9264.42 | 9746.68 | 95.05 |
| P3E_CPU0_PE3_RISER2_RX_DN_7 | 9279.5300000000007 | 9650.7199999999993 | 96.15 |
| P3E_CPU0_PE3_RISER2_RX_DP_0 | 9921.69 | 10316.129999999999 | 96.18 |
| P3E_CPU0_PE3_RISER2_RX_DP_1 | 9480.99 | 10011.98 | 94.7 |
| P3E_CPU0_PE3_RISER2_RX_DP_2 | 9344.24 | 9696.51 | 96.37 |
| P3E_CPU0_PE3_RISER2_RX_DP_3 | 9627.9599999999991 | 9943.77 | 96.82 |
| P3E_CPU0_PE3_RISER2_RX_DP_4 | 9448.9500000000007 | 9684.4599999999991 | 97.57 |
| P3E_CPU0_PE3_RISER2_RX_DP_5 | 9001.7199999999993 | 9397.84 | 95.78 |
| P3E_CPU0_PE3_RISER2_RX_DP_6 | 9266.59 | 9841.7900000000009 | 94.16 |
| P3E_CPU0_PE3_RISER2_RX_DP_7 | 9281.27 | 9745.84 | 95.23 |
| P3E_CPU0_PE3_RISER2_TX_C_DN_0 | 283.97000000000003 | 265.45 | 106.98 |
| P3E_CPU0_PE3_RISER2_TX_C_DN_1 | 282.37 | 274.52 | 102.86 |
| P3E_CPU0_PE3_RISER2_TX_C_DN_2 | 278.37 | 266.89 | 104.3 |
| P3E_CPU0_PE3_RISER2_TX_C_DN_3 | 771.32 | 739.82 | 104.26 |
| P3E_CPU0_PE3_RISER2_TX_C_DN_4 | 721.54 | 693.17 | 104.09 |
| P3E_CPU0_PE3_RISER2_TX_C_DN_5 | 422.19 | 368.58 | 114.55 |
| P3E_CPU0_PE3_RISER2_TX_C_DN_6 | 508.95 | 458.12 | 111.1 |
| P3E_CPU0_PE3_RISER2_TX_C_DN_7 | 395.37 | 302.64 | 130.63999999999999 |
| P3E_CPU0_PE3_RISER2_TX_C_DP_0 | 283.82 | 284.56 | 99.74 |
| P3E_CPU0_PE3_RISER2_TX_C_DP_1 | 280.97000000000003 | 278.2 | 101 |
| P3E_CPU0_PE3_RISER2_TX_C_DP_2 | 278.38 | 275.82 | 100.93 |
| P3E_CPU0_PE3_RISER2_TX_C_DP_3 | 773.97 | 831.73 | 93.06 |
| P3E_CPU0_PE3_RISER2_TX_C_DP_4 | 722.2 | 712.29 | 101.39 |
| P3E_CPU0_PE3_RISER2_TX_C_DP_5 | 422.63 | 387.7 | 109.01 |
| P3E_CPU0_PE3_RISER2_TX_C_DP_6 | 507.71 | 477.24 | 106.38 |
| P3E_CPU0_PE3_RISER2_TX_C_DP_7 | 394.64 | 370.51 | 106.51 |
| P3E_CPU0_PE3_RISER2_TX_DN_0 | 10526.55 | 10513.85 | 100.12 |
| P3E_CPU0_PE3_RISER2_TX_DN_1 | 10262.51 | 10236.98 | 100.25 |
| P3E_CPU0_PE3_RISER2_TX_DN_2 | 10266.85 | 10148.58 | 101.17 |
| P3E_CPU0_PE3_RISER2_TX_DN_3 | 9771.4699999999993 | 9733.82 | 100.39 |
| P3E_CPU0_PE3_RISER2_TX_DN_4 | 9444.49 | 9606.2099999999991 | 98.32 |
| P3E_CPU0_PE3_RISER2_TX_DN_5 | 9566.36 | 9713.0499999999993 | 98.49 |
| P3E_CPU0_PE3_RISER2_TX_DN_6 | 9592.9599999999991 | 9752.9599999999991 | 98.36 |
| P3E_CPU0_PE3_RISER2_TX_DN_7 | 9602.2199999999993 | 9686.89 | 99.13 |
| P3E_CPU0_PE3_RISER2_TX_DP_0 | 10528.99 | 10494.11 | 100.33 |
| P3E_CPU0_PE3_RISER2_TX_DP_1 | 10263.780000000001 | 10212.98 | 100.5 |
| P3E_CPU0_PE3_RISER2_TX_DP_2 | 10265.200000000001 | 10224.58 | 100.4 |
| P3E_CPU0_PE3_RISER2_TX_DP_3 | 9771.57 | 9710.8799999999992 | 100.62 |
| P3E_CPU0_PE3_RISER2_TX_DP_4 | 9442.69 | 9510.2099999999991 | 99.29 |
| P3E_CPU0_PE3_RISER2_TX_DP_5 | 9566.74 | 9617.0499999999993 | 99.48 |
| P3E_CPU0_PE3_RISER2_TX_DP_6 | 9594.5499999999993 | 9656.9599999999991 | 99.35 |
| P3E_CPU0_PE3_RISER2_TX_DP_7 | 9601.07 | 9590.89 | 100.11 |
| P3V3 | 33497.410000000003 | 58037.4 | 57.72 |
| P3V3_DB1900_VDDA | 0 | 179.29 | 0 |
| P3V3_EN | 264.02 | 282.33 | 93.51 |
| P3V3_LL | 342.68 | 537.23 | 63.79 |
| P3V3_LL_R | 306.02999999999997 | 260.5 | 117.48 |
| P3V3_MODE | 287.61 | 306.61 | 93.8 |
| P3V3_NGFF_MSATA | 1296.3499999999999 | 2632.27 | 49.25 |
| P3V3_RF | 170.33 | 138.52000000000001 | 122.96 |
| P3V3_ROVP | 163.58000000000001 | 35.76 | 457.44 |
| P3V3_SNB | 132.4 | 77 | 171.94 |
| P3V3_STBY | 85288.24 | 105282.75 | 81.010000000000005 |
| P3V3_STBY_EN | 164.58 | 136.99 | 120.14 |
| P3V3_STBY_LL | 109.02 | 586.33000000000004 | 18.59 |
| P3V3_STBY_LL_R | 299.89999999999998 | 280.5 | 106.92 |
| P3V3_STBY_MNG | 487.08 | 1509.12 | 32.28 |
| P3V3_STBY_MNG_IOH | 65.52 | 202.96 | 32.28 |
| P3V3_STBY_MNG_RMII | 146.99 | 433.72 | 33.89 |
| P3V3_STBY_MODE | 433.88 | 352 | 123.26 |
| P3V3_STBY_RF | 92.75 | 115.64 | 80.209999999999994 |
| P3V3_STBY_SNB | 99.07 | 92 | 107.69 |
| P3V3_STBY_TRIP | 106.02 | 124.33 | 85.27 |
| P3V3_STBY_VBST | 186.09 | 205.2 | 90.69 |
| P3V3_STBY_VBST_RC | 68.73 | 74 | 92.88 |
| P3V3_STBY_VDD | 209.3 | 235.2 | 88.99 |
| P3V3_STBY_VFB | 182.11 | 186.64 | 97.57 |
| P3V3_STBY_VFB_R | 108.1 | 124.5 | 86.83 |
| P3V3_STBY_VIN | 0 | 425.43 | 0 |
| P3V3_STBY_VREG | 387.51 | 332.38 | 116.59 |
| P3V3_TRIP | 199.17 | 127.46 | 156.26 |
| P3V3_VBST | 150.88 | 163.19999999999999 | 92.45 |
| P3V3_VBST_RC | 46 | 46 | 100 |
| P3V3_VDD | 261.24 | 251.7 | 103.79 |
| P3V3_VFB | 217.33 | 191.64 | 113.41 |
| P3V3_VFB_R | 330.17 | 335.5 | 98.41 |
| P3V3_VIN | 0 | 479.83 | 0 |
| P3V3_VREG | 419.8 | 443.1 | 94.74 |
| P3V_BAT | 5220.21 | 6211.74 | 84.04 |
| P3V_BAT_R | 66.69 | 73.05 | 91.3 |
| P3V_BAT_SOURCE | 1836.14 | 2018.43 | 90.97 |
| P5V | 19958.13 | 28658.02 | 69.64 |
| P5V_CC | 571.23 | 477.2 | 119.7 |
| P5V_EN_R | 340.46 | 303.89 | 112.03 |
| P5V_HDD | 1576.64 | 2224.59 | 70.87 |
| P5V_HDPR1 | 124.56 | 501.05 | 24.86 |
| P5V_LL | 413.54 | 497.05 | 83.2 |
| P5V_LL_R | 0 | 117.27 | 0 |
| P5V_MODE | 576.9 | 282.52999999999997 | 204.19 |
| P5V_RF | 123.05 | 107.12 | 114.87 |
| P5V_ROVP | 435.43 | 273.04000000000002 | 159.47 |
| P5V_SNB | 112.79 | 59.74 | 188.81 |
| P5V_STBY | 60336.75 | 55987.55 | 107.77 |
| P5V_TRIP | 202.47 | 199.95 | 101.26 |
| P5V_USB_FRONT | 596.28 | 791.78 | 75.31 |
| P5V_USB_FRONT_R | 169.11 | 29.74 | 568.61 |
| P5V_USB_INT | 5109.49 | 5039.63 | 101.39 |
| P5V_USB_INT_R | 64.599999999999994 | 170.83 | 37.81 |
| P5V_VBST | 97.61 | 18.5 | 527.63 |
| P5V_VBST_RC | 107.95 | 115.6 | 93.38 |
| P5V_VDD | 444.1 | 382.76 | 116.02 |
| P5V_VFB | 465.82 | 392.98 | 118.53 |
| P5V_VFB_R | 45.43 | 45.67 | 99.47 |
| P5V_VIN | 0 | 713.22 | 0 |
| P5V_VREG | 268.69 | 242 | 111.03 |
| PCH_DIMM_RDY | 4889 | 4366.87 | 111.96 |
| PCH_GP56_PLD_TCK | 3490.46 | 1984.67 | 175.87 |
| PCH_LPC_LAD0 | 452.02 | 430.18 | 105.08 |
| PCH_LPC_LAD1 | 442.98 | 419.18 | 105.68 |
| PCH_LPC_LAD2 | 265.5 | 276.77999999999997 | 95.92 |
| PCH_LPC_LAD3 | 542.57000000000005 | 532.17999999999995 | 101.95 |
| PCH_VCCPFUSE_3P3_R | 243.46 | 267.81 | 90.91 |
| PCH_XCLK_BIASREF | 124.79 | 106.55 | 117.12 |
| PCH_XCLK_BIASREF_R | 122.69 | 40.47 | 303.17 |
| PCIE_PCH_PCIE_RCOMP | 99.02 | 95.31 | 103.9 |
| PCIE_SLOT0_CONFIG | 7873.54 | 5510.55 | 142.88 |
| PCIE_SLOT1_CONFIG | 5991.61 | 4053.03 | 147.83000000000001 |
| PCIE_SLOT_CPRSNT1_N | 208.03 | 210.2 | 98.97 |
| PCIE_SLOT_CPRSNT2_N | 233.26 | 275.62 | 84.63 |
| PCIE_SLOT_CPRSNT3_N | 203.8 | 221.16 | 92.15 |
| PCIE_SLOT_CPRSNT4_N | 210.78 | 231.91 | 90.89 |
| PCIE_SLOT_CPRSNT5_N | 133.65 | 141.47 | 94.47 |
| PCIE_SLOT_CPRSNT6_N | 195.42 | 200 | 97.71 |
| PD_BIOS_RCVR_BOOT_N | 195.54 | 237.73 | 82.25 |
| PD_CKMNG_OE_N | 221.86 | 123.4 | 179.79 |
| PD_CLK_OE_EN_L | 328.87 | 223.43 | 147.19 |
| PD_CPU0_BIST_ENABLE | 760.85 | 722.64 | 105.29 |
| PD_CPU0_ERRS_B0 | 283.31 | 202.13 | 140.16 |
| PD_CPU0_ERRS_DIR | 359.08 | 217.58 | 165.03 |
| PD_CPU0_FIVR_FAULT_OE_N | 146.88 | 154.35 | 95.16 |
| PD_CPU0_TXT_PLTEN | 365.13 | 366.04 | 99.75 |
| PD_CPU1_BIST_ENABLE | 682.78 | 667.19 | 102.34 |
| PD_CPU1_ERRS_B0 | 319.81 | 346.42 | 92.32 |
| PD_CPU1_ERRS_DIR | 283.57 | 175.87 | 161.24 |
| PD_CPU1_FIVR_FAULT_OE_N | 129.26 | 95.92 | 134.76 |
| PD_CPU1_TXT_PLTEN | 430.51 | 450.74 | 95.51 |
| PD_DB1900Z_SMB_SA0 | 177.78 | 198.23 | 89.69 |
| PD_DB1900Z_SMB_SA1 | 172.26 | 179.15 | 96.15 |
| PD_DIR_0 | 163.89 | 183.06 | 89.53 |
| PD_DIR_1 | 259.47000000000003 | 291.25 | 89.09 |
| PD_DIR_2 | 204.15 | 86.06 | 237.22 |
| PD_EU95_9 | 240.1 | 289.72000000000003 | 82.87 |
| PD_FF_D_CATERR | 261.99 | 187.75 | 139.54 |
| PD_GSXDIN | 166.87 | 171.04 | 97.56 |
| PD_GTLREF_0 | 194.64 | 212.65 | 91.53 |
| PD_GTLREF_1 | 152.52000000000001 | 182.4 | 83.62 |
| PD_INTEGRATED_CLK_DIS | 182.84 | 56.75 | 322.18 |
| PD_ME_RCVR_BOOT | 158 | 158 | 100 |
| PD_ME_RCVR_N | 157.5 | 157.5 | 100 |
| PD_PCH_GP51_GSXDOUT | 283.64999999999998 | 294.99 | 96.16 |
| PD_PCH_SSTCTL | 437.68 | 500.84 | 87.39 |
| PD_PCH_USBCOMP | 168.03 | 112.75 | 149.03 |
| PD_PGDMON | 373.89 | 374.45 | 99.85 |
| PD_PV_TRKG_FRU_A2 | 185.21 | 178.03 | 104.03 |
| PD_PV_TRKG_FRU_WP | 230.85 | 197.14 | 117.1 |
| PD_PWRGD_PORST | 195.28 | 202.12 | 96.62 |
| PD_RMII1_RXER_1 | 143.07 | 155.99 | 91.71 |
| PD_RMII1_RXER_2 | 147.12 | 155.06 | 94.88 |
| PD_RST_RTCRST_N | 271.16000000000003 | 291.05 | 93.16 |
| PD_SAS0_B11 | 183.9 | 36.04 | 510.26 |
| PD_SAS1_B11 | 201.21 | 30.87 | 651.78 |
| PD_SLOT1_PRSNT1_N | 160.66 | 161.86000000000001 | 99.26 |
| PD_SPI_HEADER | 85.42 | 41 | 208.34 |
| PD_TD_IREF | 238.56 | 155.16999999999999 | 153.74 |
| PD_THERMTRIP_PORST | 167.56 | 188 | 89.13 |
| PD_TOP_SWAP | 217.86 | 206.66 | 105.42 |
| PD_USB2VRES | 241.49 | 275 | 87.82 |
| PD_XDP_BUF_BI0 | 134.46 | 144.30000000000001 | 93.18 |
| PD_XDP_BUF_BI2 | 130.22999999999999 | 134.1 | 97.12 |
| PD_ZQ | 216.77 | 210.78 | 102.84 |
| PECI_BMC | 9601.34 | 7799.43 | 123.1 |
| PECI_CPU_G | 13442.53 | 11730.02 | 114.6 |
| PECI_PCH | 513.66 | 530.96 | 96.74 |
| PEDET_SEL | 151.21 | 145.27000000000001 | 104.09 |
| PH_CH0 | 382.57 | 411.8 | 92.9 |
| PH_CH1 | 186.79 | 203.6 | 91.74 |
| PMBUS_ALERT_CPLD_OUT | 159.03 | 180.1 | 88.3 |
| PMU_SUS_CLK_NGFF | 379.3 | 306.19 | 123.88 |
| POWER_FAIL | 21006.52 | 14373.42 | 146.15 |
| POWER_FAIL_1_R | 25336.36 | 18048.330000000002 | 140.38 |
| POWER_FAIL_BMC | 496.3 | 527.17999999999995 | 94.14 |
| POWER_FAIL_CPLD | 461.92 | 524.66 | 88.04 |
| POWER_FAIL_N | 29913.61 | 27226.55 | 109.87 |
| POWER_SET | 1582.24 | 1128.5 | 140.21 |
| PQ33_B | 96.25 | 109.95 | 87.54 |
| PQ33_E | 51.01 | 54.62 | 93.38 |
| PS_REDUNDANT_LOST_N | 21811.9 | 19445.849999999999 | 112.17 |
| PU_CKMNG_OE | 283.81 | 231.24 | 122.73 |
| PU_CPU0_BMCINIT | 633.24 | 568.62 | 111.36 |
| PU_CPU0_EAR_G_N | 388.76 | 453.25 | 85.77 |
| PU_CPU0_FRMAGENT | 559.30999999999995 | 553.04 | 101.13 |
| PU_CPU0_SAFE_MODE_BOOT | 1574.04 | 1948.43 | 80.790000000000006 |
| PU_CPU0_SKTOCC_FRBY | 118.34 | 131.33000000000001 | 90.11 |
| PU_CPU0_SOCKET_ID_0 | 542.29999999999995 | 626.83000000000004 | 86.51 |
| PU_CPU0_SOCKET_ID_1 | 389.88 | 455.25 | 85.64 |
| PU_CPU0_TXT_AGENT | 445.03 | 489.34 | 90.95 |
| PU_CPU1_BMCINIT | 554.16999999999996 | 552.99 | 100.21 |
| PU_CPU1_EAR_G_N | 1279.2 | 1603.14 | 79.790000000000006 |
| PU_CPU1_FRMAGENT | 461.77 | 505.87 | 91.28 |
| PU_CPU1_SAFE_MODE_BOOT | 304.13 | 370.15 | 82.16 |
| PU_CPU1_SKTOCC_FRBY | 122.49 | 111.45 | 109.91 |
| PU_CPU1_SOCKET_ID_0 | 1212.5899999999999 | 1537.84 | 78.849999999999994 |
| PU_CPU1_SOCKET_ID_1 | 1400.38 | 1683.14 | 83.2 |
| PU_CPU1_TXT_AGENT | 412.47 | 451.19 | 91.42 |
| PU_DATAIN1_SAS0 | 538.20000000000005 | 295.58999999999997 | 182.08 |
| PU_DATAIN1_SAS1 | 453.72 | 356.36 | 127.32 |
| PU_DB1900Z_100M | 225.16 | 274 | 82.17 |
| PU_DB1900Z_HI_BW | 169.46 | 181.23 | 93.5 |
| PU_DIR_HIGH_0 | 224.58 | 94.81 | 236.87 |
| PU_DIR_HIGH_1 | 170.61 | 122.15 | 139.66999999999999 |
| PU_GPIO15_SSB | 299.75 | 348.36 | 86.05 |
| PU_PCH_DSWODVREN | 450.27 | 571.69000000000005 | 78.760000000000005 |
| PU_PCH_GP73_PLD_TMS | 77.06 | 69.069999999999993 | 111.56 |
| PU_PCH_GPIO1 | 481.93 | 441.2 | 109.23 |
| PU_PCH_GPIO34 | 381.52 | 478.76 | 79.69 |
| PU_PCH_GPIO55 | 1899.98 | 1388.2 | 136.87 |
| PU_PCH_GPIO72 | 380.58 | 423.36 | 89.9 |
| PU_PCH_INTVRMEN | 248.32 | 286.87 | 86.56 |
| PU_PCH_RCIN_N | 188.91 | 218.96 | 86.28 |
| PU_PCH_RI_R_N | 458.47 | 534.80999999999995 | 85.73 |
| PU_PCH_RSVD_6 | 313.68 | 310.95999999999998 | 100.87 |
| PU_PCI_PIRQA_N | 199.85 | 193.61 | 103.22 |
| PU_PCI_PIRQB_N | 165.8 | 187.01 | 88.66 |
| PU_PCI_PIRQC_N | 218.14 | 244.02 | 89.4 |
| PU_PCI_PIRQD_N | 242.17 | 282.77999999999997 | 85.64 |
| PU_PLD1_SLEEP_N | 226.57 | 151.53 | 149.52000000000001 |
| PU_PLD_SLEEP_N | 150.37 | 93.89 | 160.16 |
| PU_PV_TRKG_FRU_A0 | 177.13 | 195.65 | 90.53 |
| PU_PV_TRKG_FRU_A1 | 165.85 | 190.28 | 87.16 |
| PU_RST_RTCRST_N | 431.75 | 463.59 | 93.13 |
| PU_SATAX0GP | 57.77 | 56.45 | 102.35 |
| PU_SATAX1GP | 403.58 | 463.21 | 87.13 |
| PU_SATAX2GP | 290.06 | 332.78 | 87.16 |
| PU_SATAX3GP | 438.54 | 506.21 | 86.63 |
| PU_SATA_PCH_SATAX_RCOMP | 179.41 | 178.67 | 100.41 |
| PU_SATA_PCH_SATA_RCOMP | 543.86 | 610.84 | 89.03 |
| PU_SGPIO_SATA_DATAOUT1 | 341.1 | 334.11 | 102.09 |
| PU_SMB_DDR_AB_VT_EN | 138.47 | 155.01 | 89.33 |
| PU_SMB_DDR_CD_VT_EN | 103.36 | 108.44 | 95.31 |
| PU_SMB_DDR_EF_VT_EN | 216.66 | 147.72 | 146.66999999999999 |
| PU_SMB_DDR_GH_VT_EN | 166.77 | 96.2 | 173.36 |
| PU_SUSACK_N | 376.64 | 447.25 | 84.21 |
| PVCCIN_CPU0 | 4288.88 | 15781.43 | 27.18 |
| PVCCIN_CPU1 | 3954.92 | 15320.38 | 25.81 |
| PVCCIN_CPU0_ALERT | 230.95 | 272.08 | 84.88 |
| PVCCIN_CPU0_BOOT1 | 92.07 | 100 | 92.07 |
| PVCCIN_CPU0_BOOT2 | 87.67 | 98.82 | 88.71 |
| PVCCIN_CPU0_BOOT3 | 85.45 | 91.82 | 93.06 |
| PVCCIN_CPU0_BOOT4 | 94.67 | 105.82 | 89.46 |
| PVCCIN_CPU0_BOOT5 | 86.42 | 98.72 | 87.55 |
| PVCCIN_CPU0_EN | 3030.98 | 3297.29 | 91.92 |
| PVCCIN_CPU0_EN1 | 140.63999999999999 | 150.69999999999999 | 93.33 |
| PVCCIN_CPU0_EN2 | 146.59 | 133.82 | 109.54 |
| PVCCIN_CPU0_EN3 | 137.68 | 143.27000000000001 | 96.1 |
| PVCCIN_CPU0_EN4 | 140.63999999999999 | 150.69999999999999 | 93.33 |
| PVCCIN_CPU0_EN5 | 145.27000000000001 | 150.04 | 96.82 |
| PVCCIN_CPU0_FAULT | 145.83000000000001 | 137.74 | 105.87 |
| PVCCIN_CPU0_GH1 | 88.62 | 9.31 | 951.85 |
| PVCCIN_CPU0_GH2 | 97.77 | 10.48 | 932.94 |
| PVCCIN_CPU0_GH3 | 90.38 | 18.48 | 489.07 |
| PVCCIN_CPU0_GH4 | 97.15 | 5.78 | 1680.71 |
| PVCCIN_CPU0_GH5 | 90.83 | 4.5199999999999996 | 2009.54 |
| PVCCIN_CPU0_GL1 | 65.95 | 69.5 | 94.89 |
| PVCCIN_CPU0_GL2 | 58.67 | 59.09 | 99.28 |
| PVCCIN_CPU0_GL3 | 59.9 | 60.23 | 99.45 |
| PVCCIN_CPU0_GL4 | 88.37 | 102.09 | 86.56 |
| PVCCIN_CPU0_GL5 | 88.41 | 112.09 | 78.87 |
| PVCCIN_CPU0_IMON | 172.73 | 163.63999999999999 | 105.56 |
| PVCCIN_CPU0_ISEN1N | 2048.6799999999998 | 1759.83 | 116.41 |
| PVCCIN_CPU0_ISEN1P | 2056.75 | 1796.21 | 114.5 |
| PVCCIN_CPU0_ISEN2N | 1663.77 | 1466.62 | 113.44 |
| PVCCIN_CPU0_ISEN2P | 1693.54 | 1421.46 | 119.14 |
| PVCCIN_CPU0_ISEN3N | 1389.96 | 1264.69 | 109.91 |
| PVCCIN_CPU0_ISEN3P | 1415.18 | 1174.26 | 120.52 |
| PVCCIN_CPU0_ISEN4N | 1270.2 | 1089.54 | 116.58 |
| PVCCIN_CPU0_ISEN4P | 1309.8800000000001 | 1135.43 | 115.36 |
| PVCCIN_CPU0_ISEN5N | 1780.54 | 1623.63 | 109.66 |
| PVCCIN_CPU0_ISEN5P | 1768.95 | 1502.69 | 117.72 |
| PVCCIN_CPU0_PG | 173.02 | 169.16 | 102.28 |
| PVCCIN_CPU0_PHASE1 | 95.23 | 107.63 | 88.48 |
| PVCCIN_CPU0_PHASE2 | 90.83 | 106.65 | 85.16 |
| PVCCIN_CPU0_PHASE3 | 89.48 | 98.65 | 90.7 |
| PVCCIN_CPU0_PHASE4 | 99.61 | 113.65 | 87.65 |
| PVCCIN_CPU0_PHASE5 | 91.13 | 105.25 | 86.58 |
| PVCCIN_CPU0_PHASE1_R | 47 | 47 | 100 |
| PVCCIN_CPU0_PHASE2_R | 47.4 | 47.48 | 99.83 |
| PVCCIN_CPU0_PHASE3_R | 47.23 | 46.48 | 101.61 |
| PVCCIN_CPU0_PHASE4_R | 47.4 | 47.48 | 99.83 |
| PVCCIN_CPU0_PHASE5_R | 46.08 | 46.18 | 99.78 |
| PVCCIN_CPU0_PWM1 | 1229.3599999999999 | 1447.92 | 84.91 |
| PVCCIN_CPU0_PWM2 | 1051.8 | 1101.8399999999999 | 95.46 |
| PVCCIN_CPU0_PWM3 | 1301.32 | 765.59 | 169.98 |
| PVCCIN_CPU0_PWM4 | 973.32 | 913.74 | 106.52 |
| PVCCIN_CPU0_PWM5 | 1421.71 | 1256 | 113.19 |
| PVCCIN_CPU0_PWRGD_R | 161.19 | 156.11000000000001 | 103.25 |
| PVCCIN_CPU0_SADDRL | 183.29 | 10.45 | 1753.93 |
| PVCCIN_CPU0_SADDRM | 168.8 | 12.7 | 1329.12 |
| PVCCIN_CPU0_SW#1 | 366.82 | 483.63 | 75.849999999999994 |
| PVCCIN_CPU0_SW#2 | 366.39 | 439.02 | 83.46 |
| PVCCIN_CPU0_SW#3 | 386.07 | 433.02 | 89.16 |
| PVCCIN_CPU0_SW#4 | 386.07 | 443.46 | 87.06 |
| PVCCIN_CPU0_SW#5 | 386.84 | 438.15 | 88.29 |
| PVCCIN_CPU0_SW#1_N | 92.42 | 67.52 | 136.87 |
| PVCCIN_CPU0_SW#1_R | 43.99 | 44.11 | 99.73 |
| PVCCIN_CPU0_SW#2_N | 150.59 | 47.12 | 319.60000000000002 |
| PVCCIN_CPU0_SW#2_R | 40.19 | 40.29 | 99.75 |
| PVCCIN_CPU0_SW#3_N | 149.85 | 54.86 | 273.14999999999998 |
| PVCCIN_CPU0_SW#3_R | 40.270000000000003 | 40.659999999999997 | 99.03 |
| PVCCIN_CPU0_SW#4_N | 145.97 | 60.13 | 242.76 |
| PVCCIN_CPU0_SW#4_R | 39.47 | 39.520000000000003 | 99.88 |
| PVCCIN_CPU0_SW#5_N | 160.84 | 126.6 | 127.05 |
| PVCCIN_CPU0_SW#5_R | 42 | 42.08 | 99.82 |
| PVCCIN_CPU0_TMON1 | 188.26 | 212.39 | 88.64 |
| PVCCIN_CPU0_TMON2 | 177.77 | 193.51 | 91.87 |
| PVCCIN_CPU0_TMON3 | 189.96 | 204.96 | 92.68 |
| PVCCIN_CPU0_TMON4 | 188.11 | 210.39 | 89.41 |
| PVCCIN_CPU0_TMON5 | 200.94 | 195.43 | 102.82 |
| PVCCIN_CPU0_TSEN | 213.53 | 44.17 | 483.44 |
| PVCCIN_CPU0_TSEN_R | 1100.3499999999999 | 1329.35 | 82.77 |
| PVCCIN_CPU0_VADDR | 146.08000000000001 | 165.5 | 88.27 |
| PVCCIN_CPU0_VCC1 | 181.89 | 185.16 | 98.24 |
| PVCCIN_CPU0_VCC2 | 169.59 | 174.96 | 96.93 |
| PVCCIN_CPU0_VCC3 | 174.42 | 178.96 | 97.46 |
| PVCCIN_CPU0_VCC4 | 170.79 | 174.96 | 97.61 |
| PVCCIN_CPU0_VCC5 | 173.12 | 181.96 | 95.14 |
| PVCCIN_CPU0_VCLK | 235.01 | 320.58999999999997 | 73.31 |
| PVCCIN_CPU0_VD15 | 190.5 | 205.21 | 92.83 |
| PVCCIN_CPU0_VDD | 209.14 | 212.1 | 98.6 |
| PVCCIN_CPU0_VDIO | 242.13 | 296.33 | 81.709999999999994 |
| PVCCIN_CPU0_VIN | 2370.7199999999998 | 5038.0200000000004 | 47.06 |
| PVCCIN_CPU0_VINSEN | 382.5 | 345.82 | 110.61 |
| PVCCIN_CPU0_VR_EN | 113.79 | 135.19 | 84.17 |
| PVCCIN_CPU0_VSENN | 158.12 | 156.04 | 101.33 |
| PVCCIN_CPU0_VSENP | 155.81 | 168.95 | 92.22 |
| PVCCIN_CPU0_ZCD#1 | 106.31 | 117.39 | 90.56 |
| PVCCIN_CPU0_ZCD#2 | 90.34 | 95.77 | 94.33 |
| PVCCIN_CPU0_ZCD#3 | 93.34 | 98.77 | 94.5 |
| PVCCIN_CPU0_ZCD#4 | 86.68 | 89.77 | 96.56 |
| PVCCIN_CPU0_ZCD#5 | 83.62 | 84.76 | 98.65 |
| PVCCIN_CPU1_ALERT | 204.07 | 253.47 | 80.510000000000005 |
| PVCCIN_CPU1_BOOT1 | 98.57 | 113.82 | 86.6 |
| PVCCIN_CPU1_BOOT2 | 97.32 | 110.82 | 87.82 |
| PVCCIN_CPU1_BOOT3 | 94.61 | 99.23 | 95.34 |
| PVCCIN_CPU1_BOOT4 | 94.92 | 104.75 | 90.61 |
| PVCCIN_CPU1_BOOT5 | 97.38 | 107.65 | 90.46 |
| PVCCIN_CPU1_EN | 24375.58 | 13923.8 | 175.06 |
| PVCCIN_CPU1_EN1 | 139.19 | 144.36000000000001 | 96.42 |
| PVCCIN_CPU1_EN2 | 144.36000000000001 | 150.69999999999999 | 95.79 |
| PVCCIN_CPU1_EN3 | 139.26 | 147.85 | 94.19 |
| PVCCIN_CPU1_EN4 | 139.29 | 147.19999999999999 | 94.63 |
| PVCCIN_CPU1_EN5 | 140.63999999999999 | 150.69999999999999 | 93.33 |
| PVCCIN_CPU1_FAULT | 260.16000000000003 | 230.34 | 112.95 |
| PVCCIN_CPU1_GH1 | 90.83 | 4.5199999999999996 | 2009.54 |
| PVCCIN_CPU1_GH2 | 97.15 | 5.78 | 1680.71 |
| PVCCIN_CPU1_GH3 | 92.66 | 18.48 | 501.41 |
| PVCCIN_CPU1_GH4 | 90.94 | 10.71 | 849.1 |
| PVCCIN_CPU1_GH5 | 88.62 | 9.31 | 951.85 |
| PVCCIN_CPU1_GL1 | 58.84 | 59.09 | 99.57 |
| PVCCIN_CPU1_GL2 | 58.84 | 59.09 | 99.57 |
| PVCCIN_CPU1_GL3 | 58.56 | 58.73 | 99.71 |
| PVCCIN_CPU1_GL4 | 58.81 | 59.44 | 98.95 |
| PVCCIN_CPU1_GL5 | 58.49 | 58.94 | 99.23 |
| PVCCIN_CPU1_IMON | 102.62 | 110.75 | 92.66 |
| PVCCIN_CPU1_ISEN1N | 1598.1 | 1184.3399999999999 | 134.94 |
| PVCCIN_CPU1_ISEN1P | 1712.66 | 1406.82 | 121.74 |
| PVCCIN_CPU1_ISEN2N | 1729.79 | 1702.1 | 101.63 |
| PVCCIN_CPU1_ISEN2P | 1807.02 | 1775.81 | 101.76 |
| PVCCIN_CPU1_ISEN3N | 1953.16 | 1997.55 | 97.78 |
| PVCCIN_CPU1_ISEN3P | 2015.91 | 2076.5700000000002 | 97.08 |
| PVCCIN_CPU1_ISEN4N | 2504.8200000000002 | 2291.54 | 109.31 |
| PVCCIN_CPU1_ISEN4P | 2537.0100000000002 | 2377.3200000000002 | 106.72 |
| PVCCIN_CPU1_ISEN5N | 3144.15 | 2647.74 | 118.75 |
| PVCCIN_CPU1_ISEN5P | 3259.4 | 2707.58 | 120.38 |
| PVCCIN_CPU1_PG | 263.74 | 179.35 | 147.05000000000001 |
| PVCCIN_CPU1_PHASE1 | 102.49 | 122.8 | 83.46 |
| PVCCIN_CPU1_PHASE2 | 102.64 | 119.8 | 85.68 |
| PVCCIN_CPU1_PHASE3 | 102.61 | 107.21 | 95.71 |
| PVCCIN_CPU1_PHASE4 | 98.73 | 113.03 | 87.35 |
| PVCCIN_CPU1_PHASE5 | 99.48 | 113.63 | 87.55 |
| PVCCIN_CPU1_PHASE1_R | 48.14 | 48.35 | 99.58 |
| PVCCIN_CPU1_PHASE2_R | 48.14 | 48.35 | 99.58 |
| PVCCIN_CPU1_PHASE3_R | 48.27 | 48.65 | 99.22 |
| PVCCIN_CPU1_PHASE4_R | 47.27 | 47.65 | 99.2 |
| PVCCIN_CPU1_PHASE5_R | 46.31 | 46.65 | 99.27 |
| PVCCIN_CPU1_PWM1 | 1158.28 | 1124.44 | 103.01 |
| PVCCIN_CPU1_PWM2 | 1673.71 | 1482.69 | 112.88 |
| PVCCIN_CPU1_PWM3 | 2153.3000000000002 | 1832.94 | 117.48 |
| PVCCIN_CPU1_PWM4 | 2406.17 | 2169.42 | 110.91 |
| PVCCIN_CPU1_PWM5 | 2874.62 | 2509.19 | 114.56 |
| PVCCIN_CPU1_SADDRL | 146.05000000000001 | 14.74 | 990.82 |
| PVCCIN_CPU1_SADDRM | 205.53 | 21.6 | 951.55 |
| PVCCIN_CPU1_SW#1 | 681.26 | 457.62 | 148.87 |
| PVCCIN_CPU1_SW#2 | 700.17 | 436.02 | 160.58000000000001 |
| PVCCIN_CPU1_SW#3 | 680.49 | 430.33 | 158.13 |
| PVCCIN_CPU1_SW#4 | 680.49 | 436.98 | 155.72999999999999 |
| PVCCIN_CPU1_SW#5 | 680.93 | 436.09 | 156.13999999999999 |
| PVCCIN_CPU1_SW#1_N | 223.68 | 166.05 | 134.71 |
| PVCCIN_CPU1_SW#1_R | 42 | 42.08 | 99.82 |
| PVCCIN_CPU1_SW#2_N | 141.88 | 46.66 | 304.07 |
| PVCCIN_CPU1_SW#2_R | 39.47 | 39.520000000000003 | 99.88 |
| PVCCIN_CPU1_SW#3_N | 140.08000000000001 | 50.13 | 279.44 |
| PVCCIN_CPU1_SW#3_R | 40.270000000000003 | 40.659999999999997 | 99.03 |
| PVCCIN_CPU1_SW#4_N | 142.03 | 53.19 | 267.02 |
| PVCCIN_CPU1_SW#4_R | 40.19 | 40.29 | 99.75 |
| PVCCIN_CPU1_SW#5_N | 141.66999999999999 | 63.29 | 223.84 |
| PVCCIN_CPU1_SW#5_R | 43.99 | 44.11 | 99.73 |
| PVCCIN_CPU1_TMON1 | 186.84 | 188.39 | 99.18 |
| PVCCIN_CPU1_TMON2 | 187.27 | 212.39 | 88.17 |
| PVCCIN_CPU1_TMON3 | 193.54 | 207.54 | 93.26 |
| PVCCIN_CPU1_TMON4 | 187.36 | 206.89 | 90.56 |
| PVCCIN_CPU1_TMON5 | 187.87 | 212.39 | 88.45 |
| PVCCIN_CPU1_TSEN | 135.02000000000001 | 55.43 | 243.58 |
| PVCCIN_CPU1_TSEN_R | 1484.63 | 1397.43 | 106.24 |
| PVCCIN_CPU1_VADDR | 183.15 | 202.97 | 90.24 |
| PVCCIN_CPU1_VCC1 | 200.95 | 210.96 | 95.26 |
| PVCCIN_CPU1_VCC2 | 190.45 | 195.42 | 97.46 |
| PVCCIN_CPU1_VCC3 | 171.92 | 172.96 | 99.4 |
| PVCCIN_CPU1_VCC4 | 170.36 | 179.19 | 95.07 |
| PVCCIN_CPU1_VCC5 | 158 | 157.87 | 100.08 |
| PVCCIN_CPU1_VCLK | 239.87 | 304.98 | 78.650000000000006 |
| PVCCIN_CPU1_VD15 | 218.29 | 202.2 | 107.96 |
| PVCCIN_CPU1_VDD | 312.19 | 287.58 | 108.56 |
| PVCCIN_CPU1_VDIO | 223.92 | 279.39 | 80.14 |
| PVCCIN_CPU1_VIN | 3168.11 | 5437.25 | 58.27 |
| PVCCIN_CPU1_VINSEN | 203.51 | 216.48 | 94.01 |
| PVCCIN_CPU1_VR_EN | 181.88 | 234.39 | 77.599999999999994 |
| PVCCIN_CPU1_VSENN | 150.82 | 168.63 | 89.44 |
| PVCCIN_CPU1_VSENP | 115.69 | 115.21 | 100.42 |
| PVCCIN_CPU1_ZCD#1 | 115.71 | 111.72 | 103.57 |
| PVCCIN_CPU1_ZCD#2 | 115.31 | 128.31 | 89.87 |
| PVCCIN_CPU1_ZCD#3 | 93 | 100.77 | 92.29 |
| PVCCIN_CPU1_ZCD#4 | 87.01 | 89.12 | 97.64 |
| PVCCIN_CPU1_ZCD#5 | 81.5 | 90.36 | 90.2 |
| PVCCIO | 36997.69 | 38586.01 | 95.88 |
| PVCCIO_CC | 898.75 | 641.78 | 140.04 |
| PVCCIO_CC_R | 278.07 | 190.64 | 145.86000000000001 |
| PVCCIO_EN_R | 134.72999999999999 | 115.02 | 117.14 |
| PVCCIO_QS | 87.18 | 115 | 75.8 |
| PVCCIO_SS | 112.33 | 145.02000000000001 | 77.459999999999994 |
| PVCCIO_SW | 617.89 | 737.01 | 83.84 |
| PVCCIO_VBST | 224.95 | 247.99 | 90.71 |
| PVCCIO_VBST_RR | 79.53 | 81.23 | 97.91 |
| PVCCIO_VCC | 201.99 | 166.24 | 121.5 |
| PVCCIO_VFB | 298.07 | 321.43 | 92.73 |
| PVCCIO_VFB_R | 741.07 | 749.12 | 98.93 |
| PVCCIO_VIN | 0 | 373.9 | 0 |
| PVCCIO_VO | 152.49 | 163.55000000000001 | 93.24 |
| PVCCIO_VRG5 | 247.08 | 291.82 | 84.67 |
| PVCCIO__SNB | 156.16 | 83 | 188.15 |
| PVDDQ_AB | 12845.03 | 26337.22 | 48.77 |
| PVDDQ_AB_ALERT | 107.14 | 124.57 | 86.01 |
| PVDDQ_AB_BOOT1 | 86.2 | 88.74 | 97.14 |
| PVDDQ_AB_BOOT2 | 88.71 | 99.82 | 88.87 |
| PVDDQ_AB_EN | 167.88 | 157.02000000000001 | 106.92 |
| PVDDQ_AB_EN1 | 156.62 | 190.7 | 82.13 |
| PVDDQ_AB_EN2 | 162.94999999999999 | 139.69999999999999 | 116.64 |
| PVDDQ_AB_FAULT | 270.83 | 300.27999999999997 | 90.19 |
| PVDDQ_AB_GH1 | 92.66 | 10.48 | 884.16 |
| PVDDQ_AB_GH2 | 86.42 | 10.48 | 824.59 |
| PVDDQ_AB_GL1 | 76.61 | 92.09 | 83.19 |
| PVDDQ_AB_GL2 | 58.84 | 59.09 | 99.57 |
| PVDDQ_AB_IMON | 107.41 | 136.37 | 78.77 |
| PVDDQ_AB_ISEN1N | 1411.78 | 1153.02 | 122.44 |
| PVDDQ_AB_ISEN1P | 1422.08 | 1374.97 | 103.43 |
| PVDDQ_AB_ISEN2N | 1306.79 | 1088.44 | 120.06 |
| PVDDQ_AB_ISEN2P | 1282.1300000000001 | 1194.72 | 107.32 |
| PVDDQ_AB_PG | 269.66000000000003 | 261.48 | 103.13 |
| PVDDQ_AB_PHASE1 | 94.05 | 81.19 | 115.84 |
| PVDDQ_AB_PHASE2 | 92.61 | 108.87 | 85.07 |
| PVDDQ_AB_PHASE1_R | 47.22 | 47.34 | 99.74 |
| PVDDQ_AB_PHASE2_R | 48.22 | 48.42 | 99.59 |
| PVDDQ_AB_PWM1 | 1035.81 | 935.82 | 110.68 |
| PVDDQ_AB_PWM2 | 951.75 | 803.89 | 118.39 |
| PVDDQ_AB_SADDR_L | 114.54 | 21.94 | 522.05999999999995 |
| PVDDQ_AB_SADDR_M | 200.55 | 28.19 | 711.42 |
| PVDDQ_AB_SW#1 | 366.4 | 439.52 | 83.36 |
| PVDDQ_AB_SW#2 | 367.16 | 456.83 | 80.37 |
| PVDDQ_AB_SW#1_N | 119.49 | 48.92 | 244.25 |
| PVDDQ_AB_SW#1_R | 41 | 41 | 100 |
| PVDDQ_AB_SW#2_N | 139.4 | 80.88 | 172.35 |
| PVDDQ_AB_SW#2_R | 40.880000000000003 | 41.1 | 99.46 |
| PVDDQ_AB_TMON1 | 217.21 | 252.39 | 86.06 |
| PVDDQ_AB_TMON2 | 240.26 | 241.54 | 99.47 |
| PVDDQ_AB_TSEN | 180.95 | 54.9 | 329.61 |
| PVDDQ_AB_TSEN_R | 1006.31 | 927.4 | 108.51 |
| PVDDQ_AB_VADDR | 94.62 | 100.49 | 94.16 |
| PVDDQ_AB_VCC1 | 185.49 | 204.86 | 90.55 |
| PVDDQ_AB_VCC2 | 166.21 | 170.96 | 97.22 |
| PVDDQ_AB_VCLK | 144.03 | 173.78 | 82.88 |
| PVDDQ_AB_VD15 | 145.5 | 154.04 | 94.46 |
| PVDDQ_AB_VDD | 238.4 | 276.48 | 86.23 |
| PVDDQ_AB_VDIO | 117.78 | 149.86000000000001 | 78.59 |
| PVDDQ_AB_VIN | 919.43 | 3124.92 | 29.42 |
| PVDDQ_AB_VINSEN | 424.98 | 445.86 | 95.32 |
| PVDDQ_AB_VSENN | 129.88 | 153.22999999999999 | 84.76 |
| PVDDQ_AB_VSENN_R | 4924.18 | 4371.8999999999996 | 112.63 |
| PVDDQ_AB_VSENP | 118.25 | 116.48 | 101.52 |
| PVDDQ_AB_VSENP_R | 4989.97 | 4440.8 | 112.37 |
| PVDDQ_AB_ZCD#1 | 118.35 | 136.77000000000001 | 86.53 |
| PVDDQ_AB_ZCD#2 | 80.510000000000005 | 84.77 | 94.98 |
| PVDDQ_CD | 14265.66 | 27389.59 | 52.08 |
| PVDDQ_CD_ALERT | 98.17 | 104.07 | 94.33 |
| PVDDQ_CD_BOOT1 | 120.1 | 133.82 | 89.74 |
| PVDDQ_CD_BOOT2 | 83.42 | 92.82 | 89.88 |
| PVDDQ_CD_EN | 171.29 | 173.38 | 98.79 |
| PVDDQ_CD_EN1 | 76.97 | 90.85 | 84.73 |
| PVDDQ_CD_EN2 | 213.86 | 254.5 | 84.03 |
| PVDDQ_CD_FAULT | 427.64 | 390.4 | 109.54 |
| PVDDQ_CD_GH1 | 78.040000000000006 | 14.48 | 538.92999999999995 |
| PVDDQ_CD_GH2 | 75.790000000000006 | 80.48 | 94.18 |
| PVDDQ_CD_GL1 | 80.05 | 103.23 | 77.55 |
| PVDDQ_CD_GL2 | 61.93 | 61.98 | 99.91 |
| PVDDQ_CD_IMON | 107.82 | 138.74 | 77.709999999999994 |
| PVDDQ_CD_ISEN1N | 1615.03 | 1289.98 | 125.2 |
| PVDDQ_CD_ISEN1P | 1549.01 | 1284.03 | 120.64 |
| PVDDQ_CD_ISEN2N | 1562.09 | 1663.89 | 93.88 |
| PVDDQ_CD_ISEN2P | 1643.12 | 1573.72 | 104.41 |
| PVDDQ_CD_PG | 214.52 | 215.02 | 99.77 |
| PVDDQ_CD_PHASE1 | 112.79 | 140.80000000000001 | 80.099999999999994 |
| PVDDQ_CD_PHASE2 | 141.72999999999999 | 99.8 | 142.02000000000001 |
| PVDDQ_CD_PHASE1_R | 46.14 | 46.35 | 99.56 |
| PVDDQ_CD_PHASE2_R | 100.31 | 47.65 | 210.52 |
| PVDDQ_CD_PWM1 | 1260.1500000000001 | 1065.44 | 118.28 |
| PVDDQ_CD_PWM2 | 1229.8 | 1064.07 | 115.58 |
| PVDDQ_CD_SADDR_L | 265.72000000000003 | 270.43 | 98.26 |
| PVDDQ_CD_SADDR_M | 216.96 | 173.22 | 125.25 |
| PVDDQ_CD_SW#1 | 372.36 | 465.39 | 80.010000000000005 |
| PVDDQ_CD_SW#2 | 366.39 | 468.22 | 78.25 |
| PVDDQ_CD_SW#1_N | 191.49 | 205.28 | 93.28 |
| PVDDQ_CD_SW#1_R | 40.79 | 40.92 | 99.69 |
| PVDDQ_CD_SW#2_N | 230.88 | 185.81 | 124.26 |
| PVDDQ_CD_SW#2_R | 40.07 | 40.1 | 99.93 |
| PVDDQ_CD_TMON1 | 71.680000000000007 | 70.540000000000006 | 101.62 |
| PVDDQ_CD_TMON2 | 98.87 | 33.54 | 294.79000000000002 |
| PVDDQ_CD_TSEN | 182.81 | 149.06 | 122.64 |
| PVDDQ_CD_TSEN_R | 1123.93 | 1007.49 | 111.56 |
| PVDDQ_CD_VADDR | 148.54 | 22.17 | 669.98 |
| PVDDQ_CD_VCC1 | 150.41 | 158.28 | 95.03 |
| PVDDQ_CD_VCC2 | 162.08000000000001 | 174.94 | 92.65 |
| PVDDQ_CD_VCLK | 122.4 | 135.78 | 90.15 |
| PVDDQ_CD_VD15 | 229.19 | 224.08 | 102.28 |
| PVDDQ_CD_VDD | 50.77 | 171.08 | 29.67 |
| PVDDQ_CD_VDIO | 105.42 | 110.18 | 95.68 |
| PVDDQ_CD_VIN | 1011.42 | 2847.66 | 35.520000000000003 |
| PVDDQ_CD_VINSEN | 348.72 | 387.09 | 90.09 |
| PVDDQ_CD_VSENN | 121.2 | 148.22 | 81.77 |
| PVDDQ_CD_VSENN_R | 5203.51 | 4624.8599999999997 | 112.51 |
| PVDDQ_CD_VSENP | 102.7 | 113.54 | 90.46 |
| PVDDQ_CD_VSENP_R | 5346.35 | 4648.01 | 115.02 |
| PVDDQ_CD_ZCD#1 | 68.22 | 84.48 | 80.760000000000005 |
| PVDDQ_CD_ZCD#2 | 86.28 | 105.77 | 81.569999999999993 |
| PVDDQ_EF | 13738.88 | 26237.88 | 52.36 |
| PVDDQ_EF_ALERT | 167.79 | 197.81 | 84.83 |
| PVDDQ_EF_BOOT1 | 121.92 | 110.7 | 110.14 |
| PVDDQ_EF_BOOT2 | 125.08 | 111.52 | 112.16 |
| PVDDQ_EF_EN | 151.09 | 149.84 | 100.83 |
| PVDDQ_EF_EN1 | 117.49 | 130.13999999999999 | 90.28 |
| PVDDQ_EF_EN2 | 131.66 | 128.85 | 102.18 |
| PVDDQ_EF_FAULT | 188.2 | 215.93 | 87.16 |
| PVDDQ_EF_GH1 | 67.05 | 4.93 | 1360.01 |
| PVDDQ_EF_GH2 | 80.900000000000006 | 7.22 | 1120.55 |
| PVDDQ_EF_GL1 | 76.680000000000007 | 79.7 | 96.21 |
| PVDDQ_EF_GL2 | 80.89 | 80.03 | 101.07 |
| PVDDQ_EF_IMON | 105.2 | 138.31 | 76.06 |
| PVDDQ_EF_ISEN1N | 2182.1799999999998 | 1408.21 | 154.96 |
| PVDDQ_EF_ISEN1P | 2402.38 | 1803.12 | 133.22999999999999 |
| PVDDQ_EF_ISEN2N | 1099.8499999999999 | 945.12 | 116.37 |
| PVDDQ_EF_ISEN2P | 1357.45 | 1381.61 | 98.25 |
| PVDDQ_EF_PG | 223.45 | 239.27 | 93.39 |
| PVDDQ_EF_PHASE1 | 86.78 | 80.75 | 107.47 |
| PVDDQ_EF_PHASE2 | 89.41 | 80.41 | 111.19 |
| PVDDQ_EF_PHASE1_R | 104.77 | 9 | 1164.0899999999999 |
| PVDDQ_EF_PHASE2_R | 127.63 | 8.16 | 1564.14 |
| PVDDQ_EF_PWM1 | 2158.85 | 1741.83 | 123.94 |
| PVDDQ_EF_PWM2 | 1637.96 | 1293.3699999999999 | 126.64 |
| PVDDQ_EF_SADDR_L | 229.72 | 36.97 | 621.37 |
| PVDDQ_EF_SADDR_M | 115.53 | 40.22 | 287.25 |
| PVDDQ_EF_SW#1 | 372.16 | 467.12 | 79.67 |
| PVDDQ_EF_SW#2 | 368.59 | 474.97 | 77.599999999999994 |
| PVDDQ_EF_SW#1_N | 275.95999999999998 | 236.77 | 116.55 |
| PVDDQ_EF_SW#1_R | 40.36 | 40.64 | 99.32 |
| PVDDQ_EF_SW#2_N | 244.3 | 201.37 | 121.32 |
| PVDDQ_EF_SW#2_R | 40.39 | 40.700000000000003 | 99.24 |
| PVDDQ_EF_TMON1 | 111.89 | 137.83000000000001 | 81.180000000000007 |
| PVDDQ_EF_TMON2 | 165.73 | 207.54 | 79.849999999999994 |
| PVDDQ_EF_TSEN | 181.38 | 132.1 | 137.31 |
| PVDDQ_EF_TSEN_R | 2842.39 | 1454.89 | 195.37 |
| PVDDQ_EF_VADDR | 130.38 | 167.63 | 77.78 |
| PVDDQ_EF_VCC1 | 206.77 | 230.51 | 89.7 |
| PVDDQ_EF_VCC2 | 261.33 | 292.72000000000003 | 89.28 |
| PVDDQ_EF_VCLK | 222.67 | 248.31 | 89.67 |
| PVDDQ_EF_VD15 | 158.72999999999999 | 179.4 | 88.48 |
| PVDDQ_EF_VDD | 197.82 | 235.48 | 84.01 |
| PVDDQ_EF_VDIO | 209.9 | 223.06 | 94.1 |
| PVDDQ_EF_VIN | 1615.48 | 2694.32 | 59.96 |
| PVDDQ_EF_VINSEN | 226.21 | 229.48 | 98.58 |
| PVDDQ_EF_VSENN | 100 | 109.65 | 91.2 |
| PVDDQ_EF_VSENN_R | 4636.78 | 4506.2 | 102.9 |
| PVDDQ_EF_VSENP | 100.48 | 107.52 | 93.45 |
| PVDDQ_EF_VSENP_R | 4648.75 | 4474.12 | 103.9 |
| PVDDQ_EF_ZCD#1 | 89.16 | 109.83 | 81.180000000000007 |
| PVDDQ_EF_ZCD#2 | 88.18 | 108.04 | 81.61 |
| PVDDQ_GH | 12217.34 | 25691.4 | 47.55 |
| PVDDQ_GH_ALERT | 104.3 | 120.28 | 86.71 |
| PVDDQ_GH_BOOT1 | 126.33 | 131.69999999999999 | 95.93 |
| PVDDQ_GH_BOOT2 | 133.83000000000001 | 159.69999999999999 | 83.8 |
| PVDDQ_GH_EN | 131.44999999999999 | 110.4 | 119.07 |
| PVDDQ_GH_EN1 | 93.47 | 122.92 | 76.040000000000006 |
| PVDDQ_GH_EN2 | 121.35 | 148.99 | 81.45 |
| PVDDQ_GH_FAULT | 191.17 | 224.17 | 85.28 |
| PVDDQ_GH_GH1 | 77.12 | 5.01 | 1539.31 |
| PVDDQ_GH_GH2 | 72.12 | 11.93 | 604.52 |
| PVDDQ_GH_GL1 | 72.650000000000006 | 82.7 | 87.85 |
| PVDDQ_GH_GL2 | 124.96 | 128.38 | 97.34 |
| PVDDQ_GH_IMON | 110.04 | 138.84 | 79.260000000000005 |
| PVDDQ_GH_ISEN1N | 1420.85 | 1113.5 | 127.6 |
| PVDDQ_GH_ISEN1P | 1364.77 | 1066.71 | 127.94 |
| PVDDQ_GH_ISEN2N | 731.13 | 670.57 | 109.03 |
| PVDDQ_GH_ISEN2P | 724.11 | 637.28 | 113.63 |
| PVDDQ_GH_PG | 196.9 | 218.07 | 90.29 |
| PVDDQ_GH_PHASE1 | 88.42 | 94.33 | 93.73 |
| PVDDQ_GH_PHASE2 | 87.66 | 90.33 | 97.04 |
| PVDDQ_GH_PHASE1_R | 112.47 | 2 | 5623.4 |
| PVDDQ_GH_PHASE2_R | 108.08 | 30 | 360.28 |
| PVDDQ_GH_PWM1 | 1686.33 | 1655.29 | 101.88 |
| PVDDQ_GH_PWM2 | 1228.02 | 1244.54 | 98.67 |
| PVDDQ_GH_SADDR_L | 90.79 | 34.57 | 262.64 |
| PVDDQ_GH_SADDR_M | 95.71 | 32.32 | 296.12 |
| PVDDQ_GH_SW#1 | 367.47 | 441.89 | 83.16 |
| PVDDQ_GH_SW#2 | 367.15 | 429.04 | 85.57 |
| PVDDQ_GH_SW#1_N | 107.99 | 26.64 | 405.39 |
| PVDDQ_GH_SW#1_R | 40.369999999999997 | 40.380000000000003 | 99.99 |
| PVDDQ_GH_SW#2_N | 140.38999999999999 | 67.069999999999993 | 209.31 |
| PVDDQ_GH_SW#2_R | 40 | 40 | 100 |
| PVDDQ_GH_TMON1 | 135.82 | 183.29 | 74.099999999999994 |
| PVDDQ_GH_TMON2 | 164.97 | 209.44 | 78.77 |
| PVDDQ_GH_TSEN | 181.95 | 125.83 | 144.6 |
| PVDDQ_GH_TSEN_R | 2052.98 | 1004.55 | 204.37 |
| PVDDQ_GH_VADDR | 172.64 | 70.290000000000006 | 245.61 |
| PVDDQ_GH_VCC1 | 235.92 | 205.57 | 114.76 |
| PVDDQ_GH_VCC2 | 245.5 | 268.57 | 91.41 |
| PVDDQ_GH_VCLK | 132.46 | 170.78 | 77.56 |
| PVDDQ_GH_VD15 | 199.44 | 191.05 | 104.39 |
| PVDDQ_GH_VDD | 180.53 | 160.51 | 112.47 |
| PVDDQ_GH_VDIO | 114.76 | 145.53 | 78.86 |
| PVDDQ_GH_VIN | 1577.41 | 3102.01 | 50.85 |
| PVDDQ_GH_VINSEN | 199.88 | 230.24 | 86.82 |
| PVDDQ_GH_VSENN | 107.18 | 119.99 | 89.33 |
| PVDDQ_GH_VSENN_R | 4553.53 | 4674.78 | 97.41 |
| PVDDQ_GH_VSENP | 106.46 | 107.06 | 99.44 |
| PVDDQ_GH_VSENP_R | 4627.7 | 4707.0200000000004 | 98.31 |
| PVDDQ_GH_ZCD#1 | 88.8 | 79.83 | 111.24 |
| PVDDQ_GH_ZCD#2 | 78.56 | 82.83 | 94.84 |
| PVPP_AB | 21165.67 | 15317.86 | 138.18 |
| PVPP_AB_EN | 206.73 | 163.44 | 126.49 |
| PVPP_AB_LL | 236.08 | 633.19000000000005 | 37.28 |
| PVPP_AB_LL_R | 671.84 | 582.83000000000004 | 115.27 |
| PVPP_AB_MODE | 480.83 | 338.54 | 142.03 |
| PVPP_AB_PWRGD | 8522.5400000000009 | 8110.55 | 105.08 |
| PVPP_AB_RF | 126 | 126.06 | 99.95 |
| PVPP_AB_ROVP | 220.99 | 152.19 | 145.21 |
| PVPP_AB_SNB | 0 | 71.2 | 0 |
| PVPP_AB_TRIP | 123.65 | 84.54 | 146.27000000000001 |
| PVPP_AB_VBST | 88.85 | 103.82 | 85.58 |
| PVPP_AB_VBST_RC | 60.76 | 69.36 | 87.6 |
| PVPP_AB_VDD | 240.48 | 197.2 | 121.95 |
| PVPP_AB_VFB | 216.71 | 226.13 | 95.83 |
| PVPP_AB_VFB_R | 650.75 | 650.22 | 100.08 |
| PVPP_AB_VIN | 0 | 567.15 | 0 |
| PVPP_AB_VREG | 250.64 | 200 | 125.32 |
| PVPP_CD | 11658.4 | 10462.02 | 111.44 |
| PVPP_CD_EN | 382.83 | 265.19 | 144.36000000000001 |
| PVPP_CD_LL | 339.93 | 596.96 | 56.94 |
| PVPP_CD_LL_R | 82.6 | 84.68 | 97.54 |
| PVPP_CD_MODE | 281.2 | 189.77 | 148.18 |
| PVPP_CD_PWRGD | 2039.17 | 2099.29 | 97.14 |
| PVPP_CD_RF | 142.29 | 82.62 | 172.23 |
| PVPP_CD_ROVP | 165.95 | 27.68 | 599.54 |
| PVPP_CD_SNB | 0 | 71.34 | 0 |
| PVPP_CD_TRIP | 173.09 | 42.09 | 411.25 |
| PVPP_CD_VBST | 151.34 | 162.18 | 93.32 |
| PVPP_CD_VBST_RC | 64.03 | 73.42 | 87.21 |
| PVPP_CD_VDD | 326.24 | 362.68 | 89.95 |
| PVPP_CD_VFB | 392.43 | 211.02 | 185.97 |
| PVPP_CD_VFB_R | 44.78 | 47.35 | 94.58 |
| PVPP_CD_VIN | 0 | 360.76 | 0 |
| PVPP_CD_VREG | 176.44 | 144.13999999999999 | 122.41 |
| PVPP_EF | 9329.4500000000007 | 6460.65 | 144.4 |
| PVPP_EF_EN | 272.77999999999997 | 281.36 | 96.95 |
| PVPP_EF_LL | 140.11000000000001 | 466.84 | 30.01 |
| PVPP_EF_LL_R | 315.81 | 318.08 | 99.29 |
| PVPP_EF_MODE | 498.27 | 268.89999999999998 | 185.3 |
| PVPP_EF_PWRGD | 726.9 | 632.74 | 114.88 |
| PVPP_EF_RF | 215.55 | 147.66999999999999 | 145.97 |
| PVPP_EF_ROVP | 300.95999999999998 | 210.41 | 143.04 |
| PVPP_EF_SNB | 0 | 68 | 0 |
| PVPP_EF_TRIP | 176.34 | 126.22 | 139.71 |
| PVPP_EF_VBST | 114.59 | 80.23 | 142.83000000000001 |
| PVPP_EF_VBST_RC | 119.37 | 141 | 84.66 |
| PVPP_EF_VDD | 268.97000000000003 | 298.11 | 90.22 |
| PVPP_EF_VFB | 278.45 | 281.67 | 98.86 |
| PVPP_EF_VFB_R | 350.24 | 439.1 | 79.760000000000005 |
| PVPP_EF_VIN | 0 | 577.57000000000005 | 0 |
| PVPP_EF_VREG | 251.2 | 209.14 | 120.11 |
| PVPP_GH | 12916.79 | 10537.23 | 122.58 |
| PVPP_GH_EN | 228 | 127.31 | 179.09 |
| PVPP_GH_LL | 217.95 | 731.76 | 29.78 |
| PVPP_GH_LL_R | 321.88 | 275 | 117.05 |
| PVPP_GH_MODE | 185.55 | 186.39 | 99.55 |
| PVPP_GH_PWRGD | 6912.79 | 6404.39 | 107.94 |
| PVPP_GH_RF | 245.01 | 183.14 | 133.78 |
| PVPP_GH_ROVP | 159.12 | 41.62 | 382.31 |
| PVPP_GH_SNB | 56.36 | 56.89 | 99.07 |
| PVPP_GH_TRIP | 114.24 | 31.95 | 357.57 |
| PVPP_GH_VBST | 305.14999999999998 | 186.28 | 163.81 |
| PVPP_GH_VBST_RC | 150.31 | 73 | 205.91 |
| PVPP_GH_VDD | 349.59 | 392.61 | 89.04 |
| PVPP_GH_VFB | 274.95999999999998 | 209.38 | 131.32 |
| PVPP_GH_VFB_R | 518.22 | 392.5 | 132.03 |
| PVPP_GH_VIN | 0 | 660.79 | 0 |
| PVPP_GH_VREG | 166.2 | 203.92 | 81.5 |
| PVTT_AB | 2366.75 | 5717.93 | 41.39 |
| PVTT_AB_BISENN | 2042.56 | 2059.6999999999998 | 99.17 |
| PVTT_AB_BISENP | 2113.66 | 2219.9 | 95.21 |
| PVTT_AB_BISEN_N | 39.340000000000003 | 39.340000000000003 | 100 |
| PVTT_AB_BISEN_N_R | 229.13 | 223.5 | 102.52 |
| PVTT_AB_BPWM | 1733.56 | 1487.36 | 116.55 |
| PVTT_AB_BST | 273.22000000000003 | 229.63 | 118.98 |
| PVTT_AB_BTSEN | 180.85 | 182.64 | 99.02 |
| PVTT_AB_BTSEN_R | 1850.31 | 1794.94 | 103.08 |
| PVTT_AB_BVSENN | 125.61 | 133.19999999999999 | 94.3 |
| PVTT_AB_BVSENP | 135.63999999999999 | 137.87 | 98.38 |
| PVTT_AB_LGATE | 117.63 | 100.45 | 117.1 |
| PVTT_AB_LGATE_R | 118.1 | 74.11 | 159.36000000000001 |
| PVTT_AB_PH | 198.41 | 536.59 | 36.979999999999997 |
| PVTT_AB_PVCC | 469.4 | 297.77 | 157.63999999999999 |
| PVTT_AB_RT | 123.43 | 146.32 | 84.36 |
| PVTT_AB_UGATE | 242.55 | 213.58 | 113.57 |
| PVTT_AB_UGATE_R | 195.16 | 183.11 | 106.58 |
| PVTT_AB_VSENN_R | 5304.85 | 4767.16 | 111.28 |
| PVTT_AB_VSENP_R | 5224.92 | 4797.8100000000004 | 108.9 |
| PVTT_CD | 1732.62 | 5660.69 | 30.61 |
| PVTT_CD_BISENN | 2330.25 | 1886.58 | 123.52 |
| PVTT_CD_BISENP | 2314.7600000000002 | 1763.21 | 131.28 |
| PVTT_CD_BISEN_N | 39.21 | 39.21 | 100 |
| PVTT_CD_BISEN_N_R | 180.12 | 170.98 | 105.35 |
| PVTT_CD_BPWM | 1404.75 | 1516.75 | 92.62 |
| PVTT_CD_BST | 121.1 | 25.7 | 471.2 |
| PVTT_CD_BTSEN | 117.86 | 115.63 | 101.93 |
| PVTT_CD_BTSEN_R | 1729 | 1668.97 | 103.6 |
| PVTT_CD_BVSENN | 102.3 | 104.57 | 97.83 |
| PVTT_CD_BVSENP | 109.46 | 128.28 | 85.33 |
| PVTT_CD_LGATE | 155.49 | 114.32 | 136.01 |
| PVTT_CD_LGATE_R | 66.52 | 67.19 | 99 |
| PVTT_CD_PH | 68.75 | 437.73 | 15.71 |
| PVTT_CD_PVCC | 538.63 | 317.58 | 169.6 |
| PVTT_CD_RT | 61.27 | 64.13 | 95.53 |
| PVTT_CD_UGATE | 177.44 | 167.59 | 105.88 |
| PVTT_CD_UGATE_R | 122.74 | 130.41999999999999 | 94.11 |
| PVTT_CD_VSENN_R | 4856.12 | 4369.0200000000004 | 111.15 |
| PVTT_CD_VSENP_R | 4953.93 | 4425.91 | 111.93 |
| PVTT_EF | 2178.13 | 5148.01 | 42.31 |
| PVTT_EF_BISENN | 3286.95 | 2052.48 | 160.15 |
| PVTT_EF_BISENP | 3317.3 | 2232.7800000000002 | 148.57 |
| PVTT_EF_BISEN_N | 40.94 | 40.94 | 100 |
| PVTT_EF_BISEN_N_R | 172.5 | 192.28 | 89.71 |
| PVTT_EF_BPWM | 2476.23 | 2045.72 | 121.04 |
| PVTT_EF_BST | 206.04 | 138.15 | 149.13999999999999 |
| PVTT_EF_BTSEN | 202.05 | 122.79 | 164.55 |
| PVTT_EF_BTSEN_R | 3808.16 | 2353.56 | 161.80000000000001 |
| PVTT_EF_BVSENN | 148.19 | 161.07 | 92.01 |
| PVTT_EF_BVSENP | 165.63 | 193.28 | 85.69 |
| PVTT_EF_LGATE | 170.72 | 44.69 | 382.02 |
| PVTT_EF_LGATE_R | 100.83 | 116.75 | 86.36 |
| PVTT_EF_PH | 350.8 | 464.39 | 75.540000000000006 |
| PVTT_EF_PVCC | 386.74 | 338.11 | 114.38 |
| PVTT_EF_RT | 168.62 | 197.03 | 85.58 |
| PVTT_EF_UGATE | 201.31 | 182.83 | 110.11 |
| PVTT_EF_UGATE_R | 77.03 | 79.33 | 97.1 |
| PVTT_EF_VSENN_R | 4708.12 | 4803.6400000000003 | 98.01 |
| PVTT_EF_VSENP_R | 4653.0600000000004 | 4746.93 | 98.02 |
| PVTT_GH | 2417.4699999999998 | 6315.91 | 38.28 |
| PVTT_GH_BISENN | 1864.7 | 1579.7 | 118.04 |
| PVTT_GH_BISENP | 1883.37 | 1532.07 | 122.93 |
| PVTT_GH_BISEN_N | 40 | 40 | 100 |
| PVTT_GH_BISEN_N_R | 134.07 | 26.5 | 505.92 |
| PVTT_GH_BPWM | 2374.2199999999998 | 2004.6 | 118.44 |
| PVTT_GH_BST | 237.22 | 69.89 | 339.41 |
| PVTT_GH_BTSEN | 152.84 | 153.56 | 99.53 |
| PVTT_GH_BTSEN_R | 2240.84 | 1757.71 | 127.49 |
| PVTT_GH_BVSENN | 116.8 | 137.15 | 85.16 |
| PVTT_GH_BVSENP | 142.18 | 167.02 | 85.12 |
| PVTT_GH_LGATE | 124.42 | 45.23 | 275.08999999999997 |
| PVTT_GH_LGATE_R | 69.28 | 71.45 | 96.96 |
| PVTT_GH_PH | 314.99 | 399.43 | 78.86 |
| PVTT_GH_PVCC | 435.17 | 334.43 | 130.12 |
| PVTT_GH_RT | 115.64 | 118.44 | 97.64 |
| PVTT_GH_UGATE | 169.09 | 168.57 | 100.31 |
| PVTT_GH_UGATE_R | 73.349999999999994 | 82.87 | 88.51 |
| PVTT_GH_VSENN_R | 4347.24 | 4119.3900000000003 | 105.53 |
| PVTT_GH_VSENP_R | 4304.8 | 4176.76 | 103.07 |
| PWRBTN_FP_N | 633.57000000000005 | 640.41999999999996 | 98.93 |
| PWRBTN_OUT_N | 271.52999999999997 | 264.05 | 102.83 |
| PWRGD_CK_MNG_PWRDWN_N | 157.69 | 149.41999999999999 | 105.53 |
| PWRGD_CPU0_AB_DRAM_G | 2232.4499999999998 | 2423.4299999999998 | 92.12 |
| PWRGD_CPU0_AB_DRAM_G_R | 6453.06 | 5479.54 | 117.77 |
| PWRGD_CPU0_CD_DRAM_G | 2492.65 | 2902.57 | 85.88 |
| PWRGD_CPU0_CD_DRAM_G_R | 17271.150000000001 | 10520.48 | 164.17 |
| PWRGD_CPU0_G | 19334.86 | 11394.67 | 169.68 |
| PWRGD_CPU0_LVC3 | 2886.62 | 2969.34 | 97.21 |
| PWRGD_CPU0_LVC3_R | 134.81 | 73.510000000000005 | 183.39 |
| PWRGD_CPU1_EF_DRAM_G | 2499.63 | 2982.38 | 83.81 |
| PWRGD_CPU1_EF_DRAM_G_R | 15368.05 | 12292.68 | 125.02 |
| PWRGD_CPU1_G | 19036.34 | 13512.45 | 140.88 |
| PWRGD_CPU1_GH_DRAM_G | 2424.38 | 2836.69 | 85.47 |
| PWRGD_CPU1_GH_DRAM_G_R | 15781.44 | 11815.95 | 133.56 |
| PWRGD_CPU1_LVC3 | 3075.45 | 2676.1 | 114.92 |
| PWRGD_CPU1_LVC3_R | 197.24 | 67.95 | 290.27 |
| PWRGD_CPUPWRGD | 3758.47 | 3939.27 | 95.41 |
| PWRGD_CPUPWRGD_1V | 310.37 | 286.55 | 108.31 |
| PWRGD_CPUPWRGD_NPN | 441.29 | 388.75 | 113.52 |
| PWRGD_CPUPWRGD_R | 1276.3800000000001 | 1333.45 | 95.72 |
| PWRGD_DB1900Z | 644.5 | 418 | 154.19 |
| PWRGD_DRAMPWRGD_CO | 2931.21 | 2479.79 | 118.2 |
| PWRGD_LOM_AUX_VRS | 258.36 | 117.55 | 219.79 |
| PWRGD_P1V05_PCH | 2102.02 | 1665.64 | 126.2 |
| PWRGD_P1V05_PCH_STBY_DLY | 200.28 | 239.66 | 83.57 |
| PWRGD_P1V05_STBY_PCH_P1V0_STBY | 4052.11 | 3763.94 | 107.66 |
| PWRGD_P1V26_STBY | 164.94 | 202.35 | 81.510000000000005 |
| PWRGD_P1V538_STBY | 1122.42 | 1056.43 | 106.25 |
| PWRGD_P1V538_STBY_R | 290.18 | 352.81 | 82.25 |
| PWRGD_P1V5_PCH | 6497.27 | 5702.59 | 113.94 |
| PWRGD_P1V8_STBY | 1482.93 | 904.44 | 163.96 |
| PWRGD_P3V3 | 7473.29 | 5497.02 | 135.94999999999999 |
| PWRGD_P3V3_AUX | 9458.57 | 7448.74 | 126.98 |
| PWRGD_P5V | 6927.51 | 7095.21 | 97.64 |
| PWRGD_P5V_STBY | 3951.96 | 2240.42 | 176.39 |
| PWRGD_PCH_APWROK | 2835.27 | 2630.3 | 107.79 |
| PWRGD_PCH_PWROK | 7044.87 | 6094.2 | 115.6 |
| PWRGD_PCH_PWROK_BMC | 10199.86 | 6305.75 | 161.75 |
| PWRGD_PCH_PWROK_IN | 267.2 | 278.69 | 95.88 |
| PWRGD_PCH_PWROK_OUT | 348.49 | 338.46 | 102.96 |
| PWRGD_PS_PWROK | 10127.84 | 9241.93 | 109.59 |
| PWRGD_PS_PWROK_DLY | 249.01 | 145.36000000000001 | 171.3 |
| PWRGD_PVCCIN_CPU0 | 4536.24 | 4367.7 | 103.86 |
| PWRGD_PVCCIN_CPU1 | 17139.27 | 13544.32 | 126.54 |
| PWRGD_PVCCIO | 243.33 | 237.33 | 102.53 |
| PWRGD_PVPP_PVDDQ_AB | 4369.3599999999997 | 3533.33 | 123.66 |
| PWRGD_PVPP_PVDDQ_CD | 1686.87 | 1258.31 | 134.06 |
| PWRGD_PVPP_PVDDQ_EF | 12785.14 | 8055.31 | 158.72 |
| PWRGD_PVPP_PVDDQ_GH | 12089.63 | 10161.57 | 118.97 |
| PWRGD_PVTT_CPU0_CLK_OE_N | 754.42 | 506 | 149.09 |
| PWRGD_SYS_PWROK | 6152.06 | 5954.13 | 103.32 |
| PWRGD_SYS_PWROK_BMC | 9841.5300000000007 | 6952.98 | 141.54 |
| PWRGD_SYS_PWROK_IN | 318.10000000000002 | 351.99 | 90.37 |
| PWRGD_SYS_PWROK_OUT | 471.76 | 448.58 | 105.17 |
| Q25_S | 153.30000000000001 | 99.64 | 153.85 |
| Q82_G | 146.38999999999999 | 161.93 | 90.41 |
| Q82_S | 104.57 | 118.79 | 88.03 |
| QPI_CPU0_CPU1_P0P1_CLK_DN | 5258.59 | 6045.05 | 86.99 |
| QPI_CPU0_CPU1_P0P1_CLK_DP | 5262.05 | 5979.19 | 88.01 |
| QPI_CPU0_CPU1_P0P1_DN_0 | 5584.02 | 6693.96 | 83.42 |
| QPI_CPU0_CPU1_P0P1_DN_1 | 5428.28 | 6493.5 | 83.6 |
| QPI_CPU0_CPU1_P0P1_DN_2 | 5360.12 | 6331.88 | 84.65 |
| QPI_CPU0_CPU1_P0P1_DN_3 | 5233.03 | 14339.4 | 36.49 |
| QPI_CPU0_CPU1_P0P1_DN_4 | 5114.75 | 5984.76 | 85.46 |
| QPI_CPU0_CPU1_P0P1_DN_5 | 4971.8500000000004 | 5732.66 | 86.73 |
| QPI_CPU0_CPU1_P0P1_DN_6 | 5381.33 | 6047.66 | 88.98 |
| QPI_CPU0_CPU1_P0P1_DN_7 | 4986.63 | 13555.68 | 36.79 |
| QPI_CPU0_CPU1_P0P1_DN_8 | 5078.3100000000004 | 5328.78 | 95.3 |
| QPI_CPU0_CPU1_P0P1_DN_9 | 5088.41 | 5908.56 | 86.12 |
| QPI_CPU0_CPU1_P0P1_DN_10 | 4995.58 | 13512.71 | 36.97 |
| QPI_CPU0_CPU1_P0P1_DN_11 | 4994.96 | 13376.73 | 37.340000000000003 |
| QPI_CPU0_CPU1_P0P1_DN_12 | 4985.3599999999997 | 5107.6099999999997 | 97.61 |
| QPI_CPU0_CPU1_P0P1_DN_13 | 5001.12 | 5305.49 | 94.26 |
| QPI_CPU0_CPU1_P0P1_DN_14 | 4974.53 | 5118.21 | 97.19 |
| QPI_CPU0_CPU1_P0P1_DN_15 | 4959.1499999999996 | 5052.91 | 98.14 |
| QPI_CPU0_CPU1_P0P1_DN_16 | 4987.2700000000004 | 5048.21 | 98.79 |
| QPI_CPU0_CPU1_P0P1_DN_17 | 5009.46 | 4863.51 | 103 |
| QPI_CPU0_CPU1_P0P1_DN_18 | 4966.34 | 4848.8100000000004 | 102.42 |
| QPI_CPU0_CPU1_P0P1_DN_19 | 4964.01 | 5182.91 | 95.78 |
| QPI_CPU0_CPU1_P0P1_DP_0 | 5581.44 | 6579.26 | 84.83 |
| QPI_CPU0_CPU1_P0P1_DP_1 | 5428.23 | 6378.8 | 85.1 |
| QPI_CPU0_CPU1_P0P1_DP_2 | 5362.91 | 6231.88 | 86.06 |
| QPI_CPU0_CPU1_P0P1_DP_3 | 5230.72 | 14319.38 | 36.53 |
| QPI_CPU0_CPU1_P0P1_DP_4 | 5113.6099999999997 | 6004.76 | 85.16 |
| QPI_CPU0_CPU1_P0P1_DP_5 | 4969.82 | 5752.66 | 86.39 |
| QPI_CPU0_CPU1_P0P1_DP_6 | 5378.6 | 6052.96 | 88.86 |
| QPI_CPU0_CPU1_P0P1_DP_7 | 4986.83 | 13515.68 | 36.9 |
| QPI_CPU0_CPU1_P0P1_DP_8 | 5077.62 | 5348.78 | 94.93 |
| QPI_CPU0_CPU1_P0P1_DP_9 | 5089.6000000000004 | 5908 | 86.15 |
| QPI_CPU0_CPU1_P0P1_DP_10 | 4995.8500000000004 | 13532.73 | 36.92 |
| QPI_CPU0_CPU1_P0P1_DP_11 | 4992.68 | 5352.73 | 93.27 |
| QPI_CPU0_CPU1_P0P1_DP_12 | 4984.2700000000004 | 5092.91 | 97.87 |
| QPI_CPU0_CPU1_P0P1_DP_13 | 5000.3100000000004 | 5250.79 | 95.23 |
| QPI_CPU0_CPU1_P0P1_DP_14 | 4977.8999999999996 | 5118.21 | 97.26 |
| QPI_CPU0_CPU1_P0P1_DP_15 | 4960.04 | 5052.91 | 98.16 |
| QPI_CPU0_CPU1_P0P1_DP_16 | 4987.03 | 5108.21 | 97.63 |
| QPI_CPU0_CPU1_P0P1_DP_17 | 5007.6000000000004 | 4863.51 | 102.96 |
| QPI_CPU0_CPU1_P0P1_DP_18 | 4964.1899999999996 | 5060.13 | 98.1 |
| QPI_CPU0_CPU1_P0P1_DP_19 | 4963.6000000000004 | 5242.91 | 94.67 |
| QPI_CPU0_CPU1_P1P0_CLK_DN | 4545.3999999999996 | 5313.26 | 85.55 |
| QPI_CPU0_CPU1_P1P0_CLK_DP | 4542.9799999999996 | 5333.26 | 85.18 |
| QPI_CPU0_CPU1_P1P0_DN_0 | 5272.65 | 14507.86 | 36.340000000000003 |
| QPI_CPU0_CPU1_P1P0_DN_1 | 5139.3100000000004 | 6145.88 | 83.62 |
| QPI_CPU0_CPU1_P1P0_DN_2 | 5133.3100000000004 | 14804.6 | 34.67 |
| QPI_CPU0_CPU1_P1P0_DN_3 | 4844.76 | 5018.5 | 96.54 |
| QPI_CPU0_CPU1_P1P0_DN_4 | 4793.0200000000004 | 4909.1000000000004 | 97.64 |
| QPI_CPU0_CPU1_P1P0_DN_5 | 5007.8599999999997 | 6053.22 | 82.73 |
| QPI_CPU0_CPU1_P1P0_DN_6 | 4996.4799999999996 | 14270.6 | 35.01 |
| QPI_CPU0_CPU1_P1P0_DN_7 | 4737.76 | 5721.68 | 82.8 |
| QPI_CPU0_CPU1_P1P0_DN_8 | 4848.9799999999996 | 5587.56 | 86.78 |
| QPI_CPU0_CPU1_P1P0_DN_9 | 4664.3999999999996 | 5529.32 | 84.36 |
| QPI_CPU0_CPU1_P1P0_DN_10 | 4805.2299999999996 | 5655.78 | 84.96 |
| QPI_CPU0_CPU1_P1P0_DN_11 | 4884.42 | 13768.9 | 35.47 |
| QPI_CPU0_CPU1_P1P0_DN_12 | 4733.42 | 5503.8 | 86 |
| QPI_CPU0_CPU1_P1P0_DN_13 | 4685.68 | 5291.58 | 88.55 |
| QPI_CPU0_CPU1_P1P0_DN_14 | 4845.53 | 5725.28 | 84.63 |
| QPI_CPU0_CPU1_P1P0_DN_15 | 4700.49 | 5054.3999999999996 | 93 |
| QPI_CPU0_CPU1_P1P0_DN_16 | 4665.07 | 5521.42 | 84.49 |
| QPI_CPU0_CPU1_P1P0_DN_17 | 5078.57 | 14004.74 | 36.26 |
| QPI_CPU0_CPU1_P1P0_DN_18 | 5073.78 | 14478.66 | 35.04 |
| QPI_CPU0_CPU1_P1P0_DN_19 | 5252.18 | 14534.86 | 36.14 |
| QPI_CPU0_CPU1_P1P0_DP_0 | 5273.56 | 6286.02 | 83.89 |
| QPI_CPU0_CPU1_P1P0_DP_1 | 5142.87 | 6125.88 | 83.95 |
| QPI_CPU0_CPU1_P1P0_DP_2 | 5133.26 | 14804.6 | 34.67 |
| QPI_CPU0_CPU1_P1P0_DP_3 | 4846.8100000000004 | 5018.5 | 96.58 |
| QPI_CPU0_CPU1_P1P0_DP_4 | 4796.24 | 4989.1000000000004 | 96.13 |
| QPI_CPU0_CPU1_P1P0_DP_5 | 5006.1000000000004 | 6053.22 | 82.7 |
| QPI_CPU0_CPU1_P1P0_DP_6 | 4994.62 | 14270.6 | 35 |
| QPI_CPU0_CPU1_P1P0_DP_7 | 4741.95 | 5621.68 | 84.35 |
| QPI_CPU0_CPU1_P1P0_DP_8 | 4849.3900000000003 | 5673.4 | 85.48 |
| QPI_CPU0_CPU1_P1P0_DP_9 | 4664.07 | 5609.32 | 83.15 |
| QPI_CPU0_CPU1_P1P0_DP_10 | 4801.93 | 13496.66 | 35.58 |
| QPI_CPU0_CPU1_P1P0_DP_11 | 4886.03 | 13768.9 | 35.49 |
| QPI_CPU0_CPU1_P1P0_DP_12 | 4734.66 | 5503.8 | 86.03 |
| QPI_CPU0_CPU1_P1P0_DP_13 | 4684.34 | 5271.58 | 88.86 |
| QPI_CPU0_CPU1_P1P0_DP_14 | 4842.96 | 5725.28 | 84.59 |
| QPI_CPU0_CPU1_P1P0_DP_15 | 4703.6499999999996 | 5054.3999999999996 | 93.06 |
| QPI_CPU0_CPU1_P1P0_DP_16 | 4664.91 | 5515.58 | 84.58 |
| QPI_CPU0_CPU1_P1P0_DP_17 | 5075.37 | 14013.04 | 36.22 |
| QPI_CPU0_CPU1_P1P0_DP_18 | 5074.71 | 14398.66 | 35.24 |
| QPI_CPU0_CPU1_P1P0_DP_19 | 5250.68 | 14454.86 | 36.32 |
| QPI_CPU1_CPU0_P0P1_CLK_DN | 5175.05 | 13756.83 | 37.619999999999997 |
| QPI_CPU1_CPU0_P0P1_CLK_DP | 5177.18 | 13661.73 | 37.9 |
| QPI_CPU1_CPU0_P0P1_DN_0 | 5568.12 | 6031.7 | 92.31 |
| QPI_CPU1_CPU0_P0P1_DN_1 | 5344.47 | 5877.2 | 90.94 |
| QPI_CPU1_CPU0_P0P1_DN_2 | 5276.03 | 5822.98 | 90.61 |
| QPI_CPU1_CPU0_P0P1_DN_3 | 5135.32 | 5698.72 | 90.11 |
| QPI_CPU1_CPU0_P0P1_DN_4 | 5008.2 | 14879.14 | 33.659999999999997 |
| QPI_CPU1_CPU0_P0P1_DN_5 | 4963.7700000000004 | 14121.96 | 35.15 |
| QPI_CPU1_CPU0_P0P1_DN_6 | 5266.51 | 5894.52 | 89.35 |
| QPI_CPU1_CPU0_P0P1_DN_7 | 4900.99 | 5424.48 | 90.35 |
| QPI_CPU1_CPU0_P0P1_DN_8 | 5013.67 | 5446.38 | 92.06 |
| QPI_CPU1_CPU0_P0P1_DN_9 | 5032.18 | 13583.44 | 37.049999999999997 |
| QPI_CPU1_CPU0_P0P1_DN_10 | 4929.3599999999997 | 13483.89 | 36.56 |
| QPI_CPU1_CPU0_P0P1_DN_11 | 4882.13 | 5350.93 | 91.24 |
| QPI_CPU1_CPU0_P0P1_DN_12 | 4887.07 | 5107.6099999999997 | 95.68 |
| QPI_CPU1_CPU0_P0P1_DN_13 | 4900.38 | 13437.73 | 36.47 |
| QPI_CPU1_CPU0_P0P1_DN_14 | 4890.6099999999997 | 5197.95 | 94.09 |
| QPI_CPU1_CPU0_P0P1_DN_15 | 4886.7700000000004 | 5291.69 | 92.35 |
| QPI_CPU1_CPU0_P0P1_DN_16 | 4888.25 | 13341.13 | 36.64 |
| QPI_CPU1_CPU0_P0P1_DN_17 | 4900.08 | 5276.87 | 92.86 |
| QPI_CPU1_CPU0_P0P1_DN_18 | 4886.58 | 5252.09 | 93.04 |
| QPI_CPU1_CPU0_P0P1_DN_19 | 4917.57 | 5367.57 | 91.62 |
| QPI_CPU1_CPU0_P0P1_DP_0 | 5571.32 | 14660.36 | 38 |
| QPI_CPU1_CPU0_P0P1_DP_1 | 5342.88 | 15046.12 | 35.51 |
| QPI_CPU1_CPU0_P0P1_DP_2 | 5279.71 | 14439.76 | 36.56 |
| QPI_CPU1_CPU0_P0P1_DP_3 | 5134.5200000000004 | 14242.32 | 36.049999999999997 |
| QPI_CPU1_CPU0_P0P1_DP_4 | 5007.72 | 14799.14 | 33.840000000000003 |
| QPI_CPU1_CPU0_P0P1_DP_5 | 4966.2299999999996 | 5405.68 | 91.87 |
| QPI_CPU1_CPU0_P0P1_DP_6 | 5271.37 | 5899.82 | 89.35 |
| QPI_CPU1_CPU0_P0P1_DP_7 | 4898.25 | 13414.48 | 36.51 |
| QPI_CPU1_CPU0_P0P1_DP_8 | 5014.6000000000004 | 5460.54 | 91.83 |
| QPI_CPU1_CPU0_P0P1_DP_9 | 5030 | 5647.94 | 89.06 |
| QPI_CPU1_CPU0_P0P1_DP_10 | 4931.34 | 5640.25 | 87.43 |
| QPI_CPU1_CPU0_P0P1_DP_11 | 4878.12 | 5023.51 | 97.11 |
| QPI_CPU1_CPU0_P0P1_DP_12 | 4888.51 | 5092.91 | 95.99 |
| QPI_CPU1_CPU0_P0P1_DP_13 | 4904.8100000000004 | 13440.79 | 36.49 |
| QPI_CPU1_CPU0_P0P1_DP_14 | 4891.43 | 5137.95 | 95.2 |
| QPI_CPU1_CPU0_P0P1_DP_15 | 4889.54 | 5291.69 | 92.4 |
| QPI_CPU1_CPU0_P0P1_DP_16 | 4888.18 | 13343.13 | 36.630000000000003 |
| QPI_CPU1_CPU0_P0P1_DP_17 | 4900.55 | 5276.87 | 92.87 |
| QPI_CPU1_CPU0_P0P1_DP_18 | 4889.49 | 5252.09 | 93.1 |
| QPI_CPU1_CPU0_P0P1_DP_19 | 4921.34 | 5367.57 | 91.69 |
| QPI_CPU1_CPU0_P1P0_CLK_DN | 4511.42 | 5356.5 | 84.22 |
| QPI_CPU1_CPU0_P1P0_CLK_DP | 4509.46 | 5266.5 | 85.63 |
| QPI_CPU1_CPU0_P1P0_DN_0 | 5285.31 | 14654.02 | 36.07 |
| QPI_CPU1_CPU0_P1P0_DN_1 | 5170.5600000000004 | 14445 | 35.79 |
| QPI_CPU1_CPU0_P1P0_DN_2 | 5192.45 | 6250.82 | 83.07 |
| QPI_CPU1_CPU0_P1P0_DN_3 | 4885.92 | 6055.36 | 80.69 |
| QPI_CPU1_CPU0_P1P0_DN_4 | 4825.63 | 4909.1000000000004 | 98.3 |
| QPI_CPU1_CPU0_P1P0_DN_5 | 5060.8900000000003 | 14068.96 | 35.97 |
| QPI_CPU1_CPU0_P1P0_DN_6 | 5018.74 | 14109.88 | 35.57 |
| QPI_CPU1_CPU0_P1P0_DN_7 | 4723.76 | 5791.26 | 81.569999999999993 |
| QPI_CPU1_CPU0_P1P0_DN_8 | 4875.8999999999996 | 5980.5 | 81.53 |
| QPI_CPU1_CPU0_P1P0_DN_9 | 4688.12 | 5648.9 | 82.99 |
| QPI_CPU1_CPU0_P1P0_DN_10 | 4786.3 | 12854.24 | 37.24 |
| QPI_CPU1_CPU0_P1P0_DN_11 | 4845.51 | 5889.62 | 82.27 |
| QPI_CPU1_CPU0_P1P0_DN_12 | 4694.72 | 12787.62 | 36.71 |
| QPI_CPU1_CPU0_P1P0_DN_13 | 4717.8 | 5536.68 | 85.21 |
| QPI_CPU1_CPU0_P1P0_DN_14 | 4846.47 | 12450.42 | 38.93 |
| QPI_CPU1_CPU0_P1P0_DN_15 | 4647.3900000000003 | 12501.1 | 37.18 |
| QPI_CPU1_CPU0_P1P0_DN_16 | 4626.3900000000003 | 12487.2 | 37.049999999999997 |
| QPI_CPU1_CPU0_P1P0_DN_17 | 5012.51 | 12694.2 | 39.49 |
| QPI_CPU1_CPU0_P1P0_DN_18 | 5042.07 | 5811.36 | 86.76 |
| QPI_CPU1_CPU0_P1P0_DN_19 | 5197.79 | 12851.96 | 40.44 |
| QPI_CPU1_CPU0_P1P0_DP_0 | 5282.22 | 14582.32 | 36.22 |
| QPI_CPU1_CPU0_P1P0_DP_1 | 5173.6400000000003 | 14516.7 | 35.64 |
| QPI_CPU1_CPU0_P1P0_DP_2 | 5195.4799999999996 | 14260.22 | 36.43 |
| QPI_CPU1_CPU0_P1P0_DP_3 | 4883.59 | 14238.4 | 34.299999999999997 |
| QPI_CPU1_CPU0_P1P0_DP_4 | 4827.4399999999996 | 5974.98 | 80.790000000000006 |
| QPI_CPU1_CPU0_P1P0_DP_5 | 5062.04 | 14040.64 | 36.049999999999997 |
| QPI_CPU1_CPU0_P1P0_DP_6 | 5022.76 | 14089.86 | 35.65 |
| QPI_CPU1_CPU0_P1P0_DP_7 | 4726.96 | 5691.26 | 83.06 |
| QPI_CPU1_CPU0_P1P0_DP_8 | 4876.1499999999996 | 6060.5 | 80.459999999999994 |
| QPI_CPU1_CPU0_P1P0_DP_9 | 4684.9799999999996 | 5677.52 | 82.52 |
| QPI_CPU1_CPU0_P1P0_DP_10 | 4786.0200000000004 | 5691.38 | 84.09 |
| QPI_CPU1_CPU0_P1P0_DP_11 | 4844.8900000000003 | 5889.76 | 82.26 |
| QPI_CPU1_CPU0_P1P0_DP_12 | 4690.24 | 12756.38 | 36.770000000000003 |
| QPI_CPU1_CPU0_P1P0_DP_13 | 4716.6099999999997 | 12663.98 | 37.24 |
| QPI_CPU1_CPU0_P1P0_DP_14 | 4847.63 | 12435.96 | 38.979999999999997 |
| QPI_CPU1_CPU0_P1P0_DP_15 | 4643.1000000000004 | 5533.14 | 83.91 |
| QPI_CPU1_CPU0_P1P0_DP_16 | 4629.6400000000003 | 12489.2 | 37.07 |
| QPI_CPU1_CPU0_P1P0_DP_17 | 5014.1400000000003 | 5814.52 | 86.23 |
| QPI_CPU1_CPU0_P1P0_DP_18 | 5043.47 | 5831.36 | 86.49 |
| QPI_CPU1_CPU0_P1P0_DP_19 | 5197.63 | 5970.6 | 87.05 |
| REVISION_ID0 | 210.92 | 220.72 | 95.56 |
| REVISION_ID1 | 276.10000000000002 | 290.29000000000002 | 95.11 |
| REVISION_ID2 | 291.16000000000003 | 329.35 | 88.41 |
| REVISION_ID3 | 198.05 | 212.25 | 93.31 |
| REVISION_ID0_PCH | 472.11 | 413.63 | 114.14 |
| REVISION_ID1_PCH | 315.61 | 344.52 | 91.61 |
| REVISION_ID2_PCH | 409.68 | 470.68 | 87.04 |
| REVISION_ID3_PCH | 195.24 | 234.36 | 83.31 |
| RMII_BMC_CRS_DV | 2415.0100000000002 | 1802.06 | 134.01 |
| RMII_BMC_C_CRS_DV_1 | 172.48 | 199.55 | 86.44 |
| RMII_BMC_C_CRS_DV_2 | 290.66000000000003 | 363.51 | 79.959999999999994 |
| RMII_BMC_C_PHY_TXD0_1 | 240.1 | 303.83999999999997 | 79.02 |
| RMII_BMC_C_PHY_TXD0_2 | 164.27 | 195.02 | 84.23 |
| RMII_BMC_C_PHY_TXD1_1 | 232.72 | 247.54 | 94.01 |
| RMII_BMC_C_PHY_TXD1_2 | 195.51 | 206.34 | 94.75 |
| RMII_BMC_C_RX_ER_2 | 339.39 | 448.79 | 75.62 |
| RMII_BMC_C_TX_EN_1 | 186.48 | 250.05 | 74.58 |
| RMII_BMC_C_TX_EN_2 | 141.49 | 137.5 | 102.91 |
| RMII_BMC_PHY_TXD0 | 2321.4699999999998 | 1827.37 | 127.04 |
| RMII_BMC_PHY_TXD1 | 2401 | 1704.49 | 140.86000000000001 |
| RMII_BMC_TX_EN | 2429.23 | 1797.8 | 135.12 |
| RMII_NCSI_BMC_CRS_DV | 4895.32 | 4315.8599999999997 | 113.43 |
| RMII_NCSI_BMC_PHY_TXD0 | 4953.83 | 3816.48 | 129.80000000000001 |
| RMII_NCSI_BMC_PHY_TXD1 | 4921.82 | 3684.98 | 133.56 |
| RMII_NCSI_BMC_RX_ER | 8362.81 | 4323.2700000000004 | 193.44 |
| RMII_NCSI_BMC_TX_EN | 4987.8599999999997 | 3997.15 | 124.79 |
| RMII_NCSI_PHY_BMC_RXD0 | 5006.99 | 3910.69 | 128.03 |
| RMII_NCSI_PHY_BMC_RXD1 | 5061.7299999999996 | 3788.13 | 133.62 |
| RMII_PHY_BMC_C_RXD0_1 | 101.66 | 106.5 | 95.46 |
| RMII_PHY_BMC_C_RXD0_2 | 158.82 | 146.52000000000001 | 108.4 |
| RMII_PHY_BMC_C_RXD1_1 | 212.47 | 177.01 | 120.04 |
| RMII_PHY_BMC_C_RXD1_2 | 102.86 | 67.989999999999995 | 151.29 |
| RMII_PHY_BMC_RXCTL_1 | 212.68 | 253.14 | 84.02 |
| RMII_PHY_BMC_RXCTL_2 | 195.41 | 189.24 | 103.26 |
| RMII_PHY_BMC_RXD0 | 2524.46 | 1819.22 | 138.77000000000001 |
| RMII_PHY_BMC_RXD1 | 2374.63 | 1901.43 | 124.89 |
| ROMA0 | 10356.64 | 7704.77 | 134.41999999999999 |
| ROMA1 | 386.15 | 441.54 | 87.46 |
| ROMA2 | 396.06 | 452.04 | 87.62 |
| ROMA3 | 476.64 | 559.53 | 85.19 |
| ROMA4 | 313.99 | 333.31 | 94.2 |
| ROMA5 | 275.22000000000003 | 348.06 | 79.069999999999993 |
| ROMA6 | 230.05 | 288.79000000000002 | 79.66 |
| ROMA7 | 493.71 | 516.54 | 95.58 |
| ROMA8 | 598.15 | 690.32 | 86.65 |
| ROMA9 | 320.54000000000002 | 343.07 | 93.43 |
| ROMA10 | 238.04 | 307.54000000000002 | 77.400000000000006 |
| ROMA11 | 457.91 | 561.52 | 81.55 |
| ROMA12 | 399.03 | 510.42 | 78.180000000000007 |
| ROMA13 | 664.3 | 701.99 | 94.63 |
| ROMA14 | 293.54000000000002 | 353.57 | 83.02 |
| ROMA15 | 268.24 | 316.55 | 84.74 |
| ROMA16 | 361.23 | 366.36 | 98.6 |
| ROMA17 | 539.66 | 642.70000000000005 | 83.97 |
| ROMA18 | 425.97 | 452.53 | 94.13 |
| ROMA19 | 393.47 | 496.7 | 79.22 |
| ROMA20 | 468.69 | 553.01 | 84.75 |
| ROMA21 | 265.64999999999998 | 329.79 | 80.55 |
| ROMA22 | 467.99 | 572.08000000000004 | 81.81 |
| ROMA23 | 61.97 | 24.45 | 253.45 |
| ROMD0 | 416.23 | 443.16 | 93.92 |
| ROMD1 | 226.92 | 255.89 | 88.68 |
| ROMD2 | 421 | 435.55 | 96.66 |
| ROMD3 | 236.7 | 243.03 | 97.39 |
| ROMD4 | 193.43 | 221.53 | 87.32 |
| ROMD5 | 324.45999999999998 | 285.52999999999997 | 113.63 |
| ROMD6 | 157.19 | 159.05000000000001 | 98.83 |
| ROMD7 | 354.42 | 356.02 | 99.55 |
| ROMD0_R | 4787.8100000000004 | 2743.2 | 174.53 |
| ROMD1_R | 3925.24 | 2424.0100000000002 | 161.93 |
| ROMD2_R | 3109.66 | 2439.36 | 127.48 |
| ROW_EN | 4490.8599999999997 | 4140.84 | 108.45 |
| RSTBTN_BMC_OUT | 10228.43 | 5922.64 | 172.7 |
| RSTBTN_FP_N | 1110.25 | 750.34 | 147.97 |
| RSTBTN_OUT_N | 426.43 | 290.33999999999997 | 146.87 |
| RST_BMC_NIC_LRESET_LVC3_R_N | 421.94 | 310.39 | 135.94 |
| RST_BMC_RSTBTN_OUT_N | 6407.12 | 4137.88 | 154.84 |
| RST_CPU0_G_N | 19596.52 | 12818.39 | 152.88 |
| RST_CPU0_LVC3_N | 1202.74 | 1143.33 | 105.2 |
| RST_CPU0_LVC3_R_N | 2690.93 | 2947.55 | 91.29 |
| RST_CPU1_G_N | 17050.66 | 14287.92 | 119.34 |
| RST_CPU1_LVC3_N | 4806.51 | 3927.22 | 122.39 |
| RST_CPU1_LVC3_R_N | 175.97 | 192.79 | 91.28 |
| RST_DBG_RSTBTN_N | 941.4 | 666.71 | 141.19999999999999 |
| RST_DLY_CPURST_GATE_LVC3 | 332.29 | 174.94 | 189.95 |
| RST_DLY_CPURST_LVC3 | 185.34 | 222.38 | 83.34 |
| RST_PCH_RSTBTN_N | 5291.41 | 3732.84 | 141.75 |
| RST_PCH_RSTBTN_R_N | 138.38 | 81.849999999999994 | 169.06 |
| RST_PCIE_CPU_N | 3183.63 | 3110.69 | 102.34 |
| RST_PCIE_PCH_DEV_N | 7600.43 | 5179.3900000000003 | 146.74 |
| RST_PCIE_PCH_DEV_N_R | 216.43 | 83.17 | 260.23 |
| RST_PCIE_PCH_N | 591.5 | 527.66999999999996 | 112.1 |
| RST_PERST0_N | 26636.41 | 25021.45 | 106.45 |
| RST_PERST0_N_MID | 655.08000000000004 | 698.53 | 93.78 |
| RST_PERST1_N | 95.06 | 108.3 | 87.77 |
| RST_PERST1_N_210 | 175.28 | 208.32 | 84.14 |
| RST_PERST1_R_N | 156.16999999999999 | 174.97 | 89.26 |
| RST_PLTRST_BUF_N | 15200.08 | 10499.71 | 144.77000000000001 |
| RST_PLTRST_BUF_N_1 | 247.97 | 182.56 | 135.83000000000001 |
| RST_PLTRST_BUF_N_R | 189.95 | 36.630000000000003 | 518.57000000000005 |
| RST_PLTRST_DLY | 1715.6 | 1045.43 | 164.1 |
| RST_PLTRST_N | 11866.49 | 9346.17 | 126.97 |
| RST_RSMRST_BAV99_1 | 242.79 | 276.67 | 87.75 |
| RST_RSMRST_BAV99_2 | 137.24 | 99.6 | 137.79 |
| RST_RSMRST_BAV99_3 | 106.33 | 118.71 | 89.57 |
| RST_RSMRST_N | 10993 | 10049.780000000001 | 109.39 |
| RST_RSMRST_PCH_N | 1447.19 | 1409.26 | 102.69 |
| RST_RSMRST_R_N | 250.09 | 248.6 | 100.6 |
| RST_RTCRST_N | 1147.99 | 1327.86 | 86.45 |
| RST_SRTCRST_N | 274.2 | 243.96 | 112.4 |
| SATA0_TX_CC_DN | 3117.5 | 3246.29 | 96.03 |
| SATA0_TX_CC_DP | 3119.48 | 3350.79 | 93.1 |
| SATA0_TX_C_DN | 304.06 | 269.10000000000002 | 112.99 |
| SATA0_TX_C_DP | 301.02999999999997 | 344.1 | 87.48 |
| SATA1_TX_CC_DN | 2913.46 | 3079.79 | 94.6 |
| SATA1_TX_CC_DP | 2916.6 | 3164.79 | 92.16 |
| SATA1_TX_C_DN | 286.98 | 278.10000000000002 | 103.19 |
| SATA1_TX_C_DP | 285.69 | 274.10000000000002 | 104.23 |
| SATA2_TX_CC_DN | 2611.77 | 2756.84 | 94.74 |
| SATA2_TX_CC_DP | 2609.1999999999998 | 2842.84 | 91.78 |
| SATA2_TX_C_DN | 264.2 | 207.24 | 127.48 |
| SATA2_TX_C_DP | 266.8 | 282.10000000000002 | 94.58 |
| SATA3_TX_CC_DN | 2310.09 | 2610.34 | 88.5 |
| SATA3_TX_CC_DP | 2312.1999999999998 | 2606.84 | 88.7 |
| SATA3_TX_C_DN | 288.95 | 230.1 | 125.58 |
| SATA3_TX_C_DP | 287.5 | 294.24 | 97.71 |
| SATA4_TX_C_DN | 297.52 | 284 | 104.76 |
| SATA4_TX_C_DP | 300.87 | 358.61 | 83.9 |
| SATA4_TX_DN | 5157.54 | 5527.56 | 93.31 |
| SATA4_TX_DN_R | 463.21 | 219.4 | 211.12 |
| SATA4_TX_DP | 5157.07 | 5522.97 | 93.37 |
| SATA4_TX_DP_R | 460.92 | 291.08999999999997 | 158.34 |
| SATA5_RX_C_DN | 236.45 | 232.07 | 101.89 |
| SATA5_RX_C_DP | 236.12 | 242.07 | 97.54 |
| SATA5_TX_CC_DN | 5435.58 | 5373.48 | 101.16 |
| SATA5_TX_CC_DP | 5439.96 | 5388.48 | 100.96 |
| SATA5_TX_C_DN | 368.48 | 457.23 | 80.59 |
| SATA5_TX_C_DP | 368 | 383.23 | 96.03 |
| SATA6G_P0_RX_C_DN | 114.15 | 131.62 | 86.73 |
| SATA6G_P0_RX_C_DP | 114.12 | 129.12 | 88.38 |
| SATA6G_P0_RX_DN | 3877.22 | 3569.45 | 108.62 |
| SATA6G_P0_RX_DP | 3877.25 | 3573.45 | 108.5 |
| SATA6G_P1_RX_C_DN | 116.24 | 144.24 | 80.59 |
| SATA6G_P1_RX_C_DP | 115.2 | 141.74 | 81.28 |
| SATA6G_P1_RX_DN | 4104.7 | 3422.73 | 119.92 |
| SATA6G_P1_RX_DP | 4107.2700000000004 | 3486.73 | 117.8 |
| SATA6G_P2_RX_C_DN | 127.9 | 160.07 | 79.900000000000006 |
| SATA6G_P2_RX_C_DP | 130.18 | 162.57 | 80.08 |
| SATA6G_P2_RX_DN | 3708.39 | 3339.31 | 111.05 |
| SATA6G_P2_RX_DP | 3710.09 | 3343.31 | 110.97 |
| SATA6G_P3_RX_C_DN | 125.63 | 150.19 | 83.65 |
| SATA6G_P3_RX_C_DP | 129.55000000000001 | 152.69 | 84.85 |
| SATA6G_P3_RX_DN | 3505.31 | 3069.93 | 114.18 |
| SATA6G_P3_RX_DP | 3503.68 | 3133.93 | 111.8 |
| SATA6G_P4_RX_C_DN | 482.57 | 292.22000000000003 | 165.14 |
| SATA6G_P4_RX_C_DP | 487.12 | 300.72000000000003 | 161.97999999999999 |
| SATA6G_P4_RX_DN | 5238.7700000000004 | 4979.8599999999997 | 105.2 |
| SATA6G_P4_RX_DN_NGFF | 401.83 | 205.89 | 195.17 |
| SATA6G_P4_RX_DP | 5233.53 | 4909.8599999999997 | 106.59 |
| SATA6G_P4_RX_DP_NGFF | 404.39 | 265.95 | 152.05000000000001 |
| SATA6G_P5_RX_DN | 5568.3 | 5315.49 | 104.76 |
| SATA6G_P5_RX_DP | 5569.14 | 5347.69 | 104.14 |
| SERIAL_RXD | 182.26 | 241.41 | 75.5 |
| SERIAL_RXD_R | 430.13 | 483.35 | 88.99 |
| SERIAL_TXD | 283.95999999999998 | 277.95 | 102.16 |
| SERIAL_TXD_R | 548.13 | 688.75 | 79.58 |
| SGPIO_BMC_CLK_BUF_LVC3 | 186.11 | 206.45 | 90.15 |
| SGPIO_SATA_CLOCK | 612.65 | 269.89 | 227 |
| SGPIO_SATA_CLOCK_R1 | 2965.9 | 3217.13 | 92.19 |
| SGPIO_SATA_DATAOUT0 | 559.62 | 452.15 | 123.77 |
| SGPIO_SATA_DATAOUT0_R1 | 4031.53 | 3372.36 | 119.55 |
| SGPIO_SATA_LOAD | 664.82 | 329.23 | 201.93 |
| SGPIO_SATA_LOAD_R1 | 3388.53 | 3645.55 | 92.95 |
| SGPIO_SSATA_CLOCK | 640.36 | 282.99 | 226.28 |
| SGPIO_SSATA_CLOCK_R1 | 5296.45 | 4694.58 | 112.82 |
| SGPIO_SSATA_DATAOUT0 | 630.34 | 287.01 | 219.62 |
| SGPIO_SSATA_DATAOUT0_R1 | 5230.6400000000003 | 4811.5600000000004 | 108.71 |
| SGPIO_SSATA_LOAD | 636.57000000000005 | 464.71 | 136.97999999999999 |
| SGPIO_SSATA_LOAD_R1 | 5424.53 | 4668.4799999999996 | 116.19 |
| SKT_HOLD_N | 101.66 | 105.63 | 96.25 |
| SKT_SPIWP | 165.9 | 179.55 | 92.4 |
| SMB6_RISER2_CLK_R | 119.87 | 121.33 | 98.8 |
| SMB6_RISER2_DAT_R | 122.16 | 126.85 | 96.3 |
| SMB_0_ME_PCH_SCL | 313.89999999999998 | 304.38 | 103.13 |
| SMB_0_ME_PCH_SDA | 257.93 | 238.78 | 108.02 |
| SMB_1_ME_PCH_SCL | 312.36 | 305.88 | 102.12 |
| SMB_1_ME_PCH_SDA | 91.35 | 48 | 190.31 |
| SMB_1_ME_PCH_SDA_LT_STRAP | 461.83 | 497.44 | 92.84 |
| SMB_2_ME_PCH_SCL | 154.28 | 166.38 | 92.73 |
| SMB_2_ME_PCH_SDA | 364.06 | 426.21 | 85.42 |
| SMB_BMC_MEZZ_SCL | 5425.29 | 4489.32 | 120.85 |
| SMB_BMC_MEZZ_SDA | 5146.4399999999996 | 4107.9799999999996 | 125.28 |
| SMB_BMC_RSVD_SCL | 275.56 | 145.37 | 189.56 |
| SMB_BMC_RSVD_SDA | 280.06 | 267.94 | 104.52 |
| SMB_CLK | 1674.1 | 1299.3499999999999 | 128.84 |
| SMB_DATA | 1608.4 | 1043.3599999999999 | 154.16 |
| SMB_DDR_AB_SCL_G | 1943.66 | 2117.73 | 91.78 |
| SMB_DDR_AB_SCL_LVC2V5 | 1846.92 | 1637.85 | 112.77 |
| SMB_DDR_AB_SCL_R | 178.84 | 173.29 | 103.2 |
| SMB_DDR_AB_SDA_G | 1915.67 | 1963.73 | 97.55 |
| SMB_DDR_AB_SDA_LVC2V5 | 1880.63 | 1513.84 | 124.23 |
| SMB_DDR_AB_SDA_R | 173.01 | 192.85 | 89.71 |
| SMB_DDR_CD_SCL_G | 1965.16 | 2369.29 | 82.94 |
| SMB_DDR_CD_SCL_LVC2V5 | 7000.07 | 6891.46 | 101.58 |
| SMB_DDR_CD_SCL_R | 498.62 | 490.03 | 101.75 |
| SMB_DDR_CD_SDA_G | 1964.67 | 2450.27 | 80.180000000000007 |
| SMB_DDR_CD_SDA_LVC2V5 | 7005.04 | 6646.68 | 105.39 |
| SMB_DDR_CD_SDA_R | 469.7 | 372.79 | 126 |
| SMB_DDR_EF_SCL_G | 1936.8 | 2001.84 | 96.75 |
| SMB_DDR_EF_SCL_LVC2V5 | 1969.39 | 1914.83 | 102.85 |
| SMB_DDR_EF_SCL_R | 244.34 | 180.36 | 135.47 |
| SMB_DDR_EF_SDA_G | 1906.87 | 2003.1 | 95.2 |
| SMB_DDR_EF_SDA_LVC2V5 | 1969.04 | 1682.06 | 117.06 |
| SMB_DDR_EF_SDA_R | 232.28 | 245.94 | 94.45 |
| SMB_DDR_GH_SCL_G | 1972.61 | 2272.29 | 86.81 |
| SMB_DDR_GH_SCL_LVC2V5 | 6610.17 | 6616.71 | 99.9 |
| SMB_DDR_GH_SCL_R | 149.9 | 158.80000000000001 | 94.39 |
| SMB_DDR_GH_SDA_G | 1962.58 | 2353.29 | 83.4 |
| SMB_DDR_GH_SDA_LVC2V5 | 6618.68 | 6536.3 | 101.26 |
| SMB_DDR_GH_SDA_R | 262.74 | 232.68 | 112.92 |
| SMB_HOST_3V3_CLK | 6136.23 | 4868.45 | 126.04 |
| SMB_HOST_3V3_DATA | 6227.42 | 4636.8 | 134.30000000000001 |
| SMB_HOST_STBY_LVC3_CLK | 26520.74 | 19497.54 | 136.02000000000001 |
| SMB_HOST_STBY_LVC3_DATA | 27027.52 | 20087.84 | 134.55000000000001 |
| SMB_MAIN_CLK | 7084.05 | 3649.72 | 194.1 |
| SMB_MAIN_DATA | 7422.35 | 3650.09 | 203.35 |
| SMB_PMBUS_BMC_STBY_LVC3_CLK | 33489.81 | 27332.7 | 122.53 |
| SMB_PMBUS_BMC_STBY_LVC3_DATA | 33657.339999999997 | 27126.560000000001 | 124.08 |
| SMB_PMBUS_CLK | 1980.82 | 1332.71 | 148.63 |
| SMB_PMBUS_DATA | 1990.33 | 1346.76 | 147.79 |
| SMB_SENSOR_CLK | 35048.449999999997 | 28421.16 | 123.32 |
| SMB_SENSOR_DAT | 35032.5 | 28410.78 | 123.31 |
| SMB_SMLINK0_STBY_LVC3_CLK | 10567.28 | 8660.32 | 122.02 |
| SMB_SMLINK0_STBY_LVC3_DATA | 10934.54 | 8729.4 | 125.26 |
| SMB_TEMP_BACK_DXN | 183.05 | 179.52 | 101.97 |
| SMB_TEMP_BACK_DXN_C | 322.39999999999998 | 379.14 | 85.03 |
| SMB_TEMP_BACK_DXN_R | 277.43 | 281.22000000000003 | 98.65 |
| SMB_TEMP_BACK_DXP | 212.71 | 243.12 | 87.49 |
| SMB_TEMP_BACK_DXP_R | 255.02 | 234.67 | 108.67 |
| SMB_TEMP_BACK_SCL_R | 68.650000000000006 | 71.7 | 95.75 |
| SMB_TEMP_BACK_SDA_R | 83.47 | 99.7 | 83.72 |
| SMB_TEMP_FRONT_DXN | 253.52 | 262.7 | 96.5 |
| SMB_TEMP_FRONT_DXN_C | 177.24 | 166.96 | 106.16 |
| SMB_TEMP_FRONT_DXN_R | 288.77 | 287.25 | 100.53 |
| SMB_TEMP_FRONT_DXP | 221.42 | 241.1 | 91.84 |
| SMB_TEMP_FRONT_DXP_R | 350.3 | 449.58 | 77.92 |
| SMB_TEMP_FRONT_SCL_R | 209.04 | 187.3 | 111.61 |
| SMB_TEMP_FRONT_SDA_R | 192.22 | 150.69999999999999 | 127.55 |
| SMB_VR_STBY_LVC3_CLK | 35952.550000000003 | 28978.22 | 124.07 |
| SMB_VR_STBY_LVC3_DATA | 35790.730000000003 | 29496.99 | 121.34 |
| SML1_CLK | 664.21 | 624.75 | 106.32 |
| SML1_DATA | 685.94 | 601.69000000000005 | 114 |
| SPEAKER_PCH | 5661.56 | 5842.11 | 96.91 |
| SPI_BMCOUT_CLK | 4457.34 | 1937.46 | 230.06 |
| SPI_BMCOUT_CS0_N | 4253.3100000000004 | 2230.59 | 190.68 |
| SPI_BMCOUT_MOSI | 3697.32 | 2223.9699999999998 | 166.25 |
| SPI_DEDIPROG_DQ2 | 108.54 | 73.53 | 147.62 |
| SPI_DEDIPROG_DQ3 | 161.22999999999999 | 81.23 | 198.48 |
| SPI_PCH_CLK | 307.60000000000002 | 281 | 109.47 |
| SPI_PCH_CLK_R | 5504.87 | 4196.04 | 131.19 |
| SPI_PCH_CS0_N | 108.61 | 74.55 | 145.69 |
| SPI_PCH_CS0_N_R | 706.36 | 695 | 101.63 |
| SPI_PCH_CS0_R_N | 5606.81 | 4217.6499999999996 | 132.94 |
| SPI_PCH_CS1_N | 110.65 | 70.25 | 157.51 |
| SPI_PCH_CS1_N_R | 587.63 | 412.54 | 142.44 |
| SPI_PCH_CS_N | 367.53 | 274.75 | 133.77000000000001 |
| SPI_PCH_IO2_R | 7030.66 | 3751.12 | 187.43 |
| SPI_PCH_IO3_R | 7358.6 | 3713.41 | 198.16 |
| SPI_PCH_MISO | 232.63 | 237.52 | 97.94 |
| SPI_PCH_MISO_R | 5264.8 | 3728.65 | 141.19999999999999 |
| SPI_PCH_MOSI | 246.06 | 258.60000000000002 | 95.15 |
| SPI_PCH_MOSI_R | 5007.62 | 3748.04 | 133.61000000000001 |
| SPI_SKT0_CLK_R | 663.79 | 496.64 | 133.66 |
| SPI_SKT0_CLK_R1 | 1044.25 | 1068.3699999999999 | 97.74 |
| SPI_SKT0_HLD_R1_N | 152.22 | 109.93 | 138.47 |
| SPI_SKT0_HLD_R_N | 684.5 | 782.14 | 87.52 |
| SPI_SKT0_MISO_R | 1121.95 | 1098.74 | 102.11 |
| SPI_SKT0_MISO_R1 | 539.78 | 388.79 | 138.84 |
| SPI_SKT0_MOSI_R | 992.66 | 868.44 | 114.3 |
| SPI_SKT0_MOSI_R1 | 933.23 | 466.41 | 200.09 |
| SPI_SKT0_RESET_N | 178.34 | 164.14 | 108.65 |
| SPI_SKT0_WP_N | 1937.13 | 1743 | 111.14 |
| SPI_SKT0_WP_R1_N | 191.82 | 183.49 | 104.54 |
| SPI_SKT0_WP_R_N | 216.53 | 170.36 | 127.1 |
| SPI_SKT2_RESET_N | 156.91999999999999 | 124.93 | 125.61 |
| SRP_CPU_PWR_DEBUG_N | 7191.43 | 5660.57 | 127.04 |
| SSATA6G_0_RX_CC_DN | 111.43 | 131.21 | 84.93 |
| SSATA6G_0_RX_CC_DP | 110.4 | 128.71 | 85.77 |
| SSATA6G_0_RX_C_DN | 3800.44 | 4364.57 | 87.07 |
| SSATA6G_0_RX_C_DP | 3799.01 | 4428.57 | 85.78 |
| SSATA6G_0_TX_CC_DN | 3792.75 | 4239.3 | 89.47 |
| SSATA6G_0_TX_CC_DP | 3794.81 | 4250.16 | 89.29 |
| SSATA6G_0_TX_C_DN | 271.68 | 334.78 | 81.150000000000006 |
| SSATA6G_0_TX_C_DP | 268.92 | 260.77999999999997 | 103.12 |
| SSATA6G_1_RX_CC_DN | 119.28 | 151.54 | 78.709999999999994 |
| SSATA6G_1_RX_CC_DP | 120.49 | 149.04 | 80.84 |
| SSATA6G_1_RX_C_DN | 3702.27 | 4282.4799999999996 | 86.45 |
| SSATA6G_1_RX_C_DP | 3702.93 | 4346.4799999999996 | 85.19 |
| SSATA6G_1_TX_CC_DN | 3925.56 | 4224.0200000000004 | 92.93 |
| SSATA6G_1_TX_CC_DP | 3924.06 | 4218.16 | 93.03 |
| SSATA6G_1_TX_C_DN | 304.55 | 309.89 | 98.28 |
| SSATA6G_1_TX_C_DP | 302.2 | 315.62 | 95.75 |
| SSATA6G_2_RX_CC_DN | 118.96 | 149.87 | 79.38 |
| SSATA6G_2_RX_CC_DP | 120 | 152.37 | 78.760000000000005 |
| SSATA6G_2_RX_C_DN | 3746.11 | 4255.32 | 88.03 |
| SSATA6G_2_RX_C_DP | 3742.54 | 4259.32 | 87.87 |
| SSATA6G_2_TX_CC_DN | 3912.39 | 4152.6400000000003 | 94.21 |
| SSATA6G_2_TX_CC_DP | 3910.71 | 4158.1400000000003 | 94.05 |
| SSATA6G_2_TX_C_DN | 437.49 | 453.53 | 96.46 |
| SSATA6G_2_TX_C_DP | 435.43 | 457.53 | 95.17 |
| SSATA6G_3_RX_CC_DN | 118.02 | 145.16 | 81.3 |
| SSATA6G_3_RX_CC_DP | 119.06 | 147.66 | 80.63 |
| SSATA6G_3_RX_C_DN | 3713.72 | 4162.2700000000004 | 89.22 |
| SSATA6G_3_RX_C_DP | 3716.48 | 4166.2700000000004 | 89.2 |
| SSATA6G_3_TX_CC_DN | 4058.03 | 4167.17 | 97.38 |
| SSATA6G_3_TX_CC_DP | 4056 | 4171.75 | 97.23 |
| SSATA6G_3_TX_C_DN | 438.26 | 501.5 | 87.39 |
| SSATA6G_3_TX_C_DP | 441.45 | 505.84 | 87.27 |
| SSB_ROW_LATCH | 3676.58 | 3524.83 | 104.31 |
| SUS_STAT_N_PLD_TDI | 780.92 | 887.86 | 87.96 |
| SVID_ALERT_CPU0_N | 14779.95 | 11709.67 | 126.22 |
| SVID_ALERT_CPU0_R1_G | 458.8 | 140.16999999999999 | 327.32 |
| SVID_ALERT_CPU1_N | 19883.39 | 11168.29 | 178.03 |
| SVID_ALERT_CPU1_R1_G | 460.79 | 111.85 | 411.97 |
| SVID_CLK_CPU0 | 14811.97 | 11674.98 | 126.87 |
| SVID_CLK_CPU1 | 19687.150000000001 | 11132.3 | 176.85 |
| SVID_CLK_CPU0_R | 448.95 | 254.9 | 176.13 |
| SVID_CLK_CPU1_R | 449.47 | 253.81 | 177.09 |
| SVID_DIO_CPU0 | 14779.27 | 11688.28 | 126.45 |
| SVID_DIO_CPU1 | 19679.28 | 11166.02 | 176.24 |
| SVID_DIO_CPU0_R | 456.02 | 220.5 | 206.81 |
| SVID_DIO_CPU1_R | 440.97 | 230.81 | 191.05 |
| SWITCH_EA_N | 191.27 | 170.66 | 112.08 |
| SWITCH_EB_N | 127.7 | 108.3 | 117.91 |
| SWITCH_S0 | 11829.54 | 8400.2000000000007 | 140.82 |
| SWITCH_S1 | 14322.42 | 8184.5 | 174.99 |
| SYS_BMCOUT_MISO | 3708.17 | 2147.61 | 172.66 |
| SYS_PWRBTN_N | 8618.24 | 5293.97 | 162.79 |
| SYS_RSTBTN_N | 8000.27 | 5283.05 | 151.43 |
| TEMP_A0_BACK | 66.67 | 71.849999999999994 | 92.78 |
| TEMP_A0_FRONT | 123.77 | 144.72999999999999 | 85.52 |
| TEMP_A1_BACK | 72.650000000000006 | 86.3 | 84.18 |
| TEMP_A1_FRONT | 184.03 | 143.69999999999999 | 128.06 |
| TIMER_ALERT_CPLD_N | 20027.55 | 18000.48 | 111.26 |
| TIMER_CMP | 404.9 | 329.03 | 123.06 |
| TPM_PRSNT_N | 2211.19 | 1509.04 | 146.53 |
| TPS74801_1V26_BIAS | 191.64 | 198.5 | 96.55 |
| TPS74801_1V26_EN | 192.7 | 207.24 | 92.98 |
| TPS74801_1V26_FB | 157.29 | 124.3 | 126.54 |
| TPS74801_1V26_OUT | 0 | 777.34 | 0 |
| TPS74801_1V26_SS | 125.9 | 68.67 | 183.35 |
| TPS74801_1V538_BIAS | 198.37 | 252.89 | 78.44 |
| TPS74801_1V538_EN | 222.1 | 154.88999999999999 | 143.38999999999999 |
| TPS74801_1V538_FB | 175.31 | 205.81 | 85.18 |
| TPS74801_1V538_SS | 127.64 | 138.88999999999999 | 91.9 |
| TPS74801_P1V26_IN | 0 | 584.34 | 0 |
| TPS74801_P1V538_IN | 0 | 504.3 | 0 |
| TPS74801_P1V538_OUT | 85 | 757.05 | 11.23 |
| TPS74801_P1V5_PCH_BIAS | 185.97 | 198.89 | 93.5 |
| TPS74801_P1V5_PCH_EN | 318.05 | 307.63 | 103.39 |
| TPS74801_P1V5_PCH_FB | 148.59 | 150.18 | 98.94 |
| TPS74801_P1V5_PCH_IN | 0 | 587.87 | 0 |
| TPS74801_P1V5_PCH_OUT | 0 | 625.32000000000005 | 0 |
| TPS74801_P1V5_PCH_SS | 132.22 | 149.57 | 88.4 |
| TP_BAV99_2 | 73.78 | 87.72 | 84.11 |
| TP_BAV99_3 | 60.55 | 65.38 | 92.61 |
| TP_CATERR_DLY_FF_Q_N | 242.13 | 147.06 | 164.65 |
| TP_CKNMG_33M/SMBA | 113.29 | 136.04 | 83.28 |
| TP_CLK6_50M_CKMNG | 148.01 | 166.1 | 89.11 |
| TP_CLK7_50M_CKMNG | 93.92 | 103.41 | 90.82 |
| TP_CLKOUT_PCI_1 | 152.38999999999999 | 179 | 85.13 |
| TP_CPU0_PE_HP_SCL | 23.1 | 23.1 | 100 |
| TP_CPU0_PE_HP_SDA | 23.1 | 23.1 | 100 |
| TP_CPU0_RSVD_1 | 70.45 | 92.79 | 75.930000000000007 |
| TP_CPU0_RSVD_2 | 24.8 | 31.6 | 78.5 |
| TP_CPU0_RSVD_3 | 23.1 | 23.1 | 100 |
| TP_CPU0_RSVD_4 | 23.1 | 23.1 | 100 |
| TP_CPU0_RSVD_5 | 23.1 | 23.1 | 100 |
| TP_CPU0_RSVD_6 | 66.08 | 77.8 | 84.94 |
| TP_CPU0_RSVD_7 | 23.1 | 23.1 | 100 |
| TP_CPU0_RSVD_8 | 23.1 | 23.1 | 100 |
| TP_CPU0_RSVD_9 | 23.1 | 23.1 | 100 |
| TP_CPU0_RSVD_10 | 23.1 | 23.1 | 100 |
| TP_CPU0_RSVD_11 | 23.1 | 23.1 | 100 |
| TP_CPU0_RSVD_12 | 23.1 | 23.1 | 100 |
| TP_CPU0_RSVD_13 | 23.1 | 23.1 | 100 |
| TP_CPU0_RSVD_14 | 23.1 | 23.1 | 100 |
| TP_CPU0_RSVD_15 | 23.1 | 23.1 | 100 |
| TP_CPU0_RSVD_16 | 23.1 | 23.1 | 100 |
| TP_CPU0_RSVD_17 | 23.1 | 23.1 | 100 |
| TP_CPU0_RSVD_18 | 23.1 | 23.1 | 100 |
| TP_CPU0_RSVD_19 | 178.83 | 224.62 | 79.61 |
| TP_CPU0_RSVD_20 | 23.1 | 23.1 | 100 |
| TP_CPU0_RSVD_21 | 23.1 | 23.1 | 100 |
| TP_CPU0_RSVD_22 | 23.1 | 23.1 | 100 |
| TP_CPU0_RSVD_24 | 23.1 | 23.1 | 100 |
| TP_CPU0_RSVD_25 | 23.1 | 23.1 | 100 |
| TP_CPU0_RSVD_26 | 23.1 | 23.1 | 100 |
| TP_CPU0_RSVD_27 | 23.26 | 23.28 | 99.92 |
| TP_CPU0_RSVD_28 | 23.1 | 23.1 | 100 |
| TP_CPU0_RSVD_29 | 23.1 | 23.1 | 100 |
| TP_CPU0_RSVD_30 | 23.1 | 23.1 | 100 |
| TP_CPU0_RSVD_33 | 23.1 | 23.1 | 100 |
| TP_CPU0_RSVD_34 | 23.1 | 23.1 | 100 |
| TP_CPU0_RSVD_35 | 23.1 | 23.1 | 100 |
| TP_CPU0_RSVD_36 | 82.79 | 97.97 | 84.5 |
| TP_CPU0_RSVD_37 | 28.18 | 39.619999999999997 | 71.12 |
| TP_CPU0_RSVD_38 | 35.86 | 43.21 | 82.99 |
| TP_CPU0_RSVD_39 | 38.43 | 43.77 | 87.79 |
| TP_CPU0_RSVD_40 | 131.36000000000001 | 174.99 | 75.069999999999993 |
| TP_CPU0_RSVD_41 | 23.1 | 23.1 | 100 |
| TP_CPU0_RSVD_42 | 23.1 | 23.1 | 100 |
| TP_CPU0_RSVD_43 | 23.1 | 23.1 | 100 |
| TP_CPU0_RSVD_44 | 23.1 | 23.1 | 100 |
| TP_CPU0_RSVD_45 | 23.1 | 23.1 | 100 |
| TP_CPU0_RSVD_46 | 23.1 | 23.1 | 100 |
| TP_CPU0_RSVD_48 | 23.1 | 23.1 | 100 |
| TP_CPU0_RSVD_49 | 23.1 | 23.1 | 100 |
| TP_CPU0_RSVD_50 | 23.1 | 23.1 | 100 |
| TP_CPU0_RSVD_51 | 23.1 | 23.1 | 100 |
| TP_CPU0_RSVD_52 | 23.1 | 23.1 | 100 |
| TP_CPU0_RSVD_53 | 23.1 | 23.1 | 100 |
| TP_CPU0_RSVD_54 | 23.1 | 23.1 | 100 |
| TP_CPU0_RSVD_55 | 23.1 | 23.1 | 100 |
| TP_CPU0_RSVD_56 | 23.1 | 23.1 | 100 |
| TP_CPU0_RSVD_57 | 23.1 | 23.1 | 100 |
| TP_CPU0_RSVD_58 | 23.1 | 23.1 | 100 |
| TP_CPU0_RSVD_59 | 23.1 | 23.1 | 100 |
| TP_CPU0_RSVD_60 | 23.1 | 23.1 | 100 |
| TP_CPU0_RSVD_61 | 23.1 | 23.1 | 100 |
| TP_CPU0_RSVD_62 | 23.1 | 23.1 | 100 |
| TP_CPU0_RSVD_63 | 23.1 | 23.1 | 100 |
| TP_CPU0_RSVD_64 | 23.1 | 23.1 | 100 |
| TP_CPU0_RSVD_65 | 23.1 | 23.1 | 100 |
| TP_CPU0_RSVD_66 | 23.1 | 23.1 | 100 |
| TP_CPU0_RSVD_67 | 23.1 | 23.1 | 100 |
| TP_CPU0_RSVD_68 | 30.93 | 33.67 | 91.88 |
| TP_CPU0_RSVD_69 | 95.56 | 130.97 | 72.959999999999994 |
| TP_CPU0_RSVD_70 | 90.42 | 117.8 | 76.760000000000005 |
| TP_CPU0_RSVD_71 | 116.34 | 158.80000000000001 | 73.260000000000005 |
| TP_CPU0_RSVD_72 | 122.32 | 158.52000000000001 | 77.16 |
| TP_CPU0_RSVD_73 | 28.34 | 28.47 | 99.55 |
| TP_CPU0_RSVD_76 | 28.59 | 28.94 | 98.81 |
| TP_CPU0_RSVD_77 | 24.8 | 31.6 | 78.5 |
| TP_CPU0_RSVD_78 | 28 | 28.08 | 99.73 |
| TP_CPU0_RSVD_79 | 76.52 | 90.65 | 84.41 |
| TP_CPU0_RSVD_80 | 23.1 | 23.1 | 100 |
| TP_CPU0_RSVD_81 | 23.1 | 23.1 | 100 |
| TP_CPU0_RSVD_82 | 23.1 | 23.1 | 100 |
| TP_CPU0_RSVD_83 | 23.01 | 23.03 | 99.92 |
| TP_CPU0_TEST_0 | 1435.13 | 1928.84 | 74.400000000000006 |
| TP_CPU0_TEST_1 | 1524.84 | 2040.37 | 74.73 |
| TP_CPU0_TEST_2 | 1632.16 | 1772.36 | 92.09 |
| TP_CPU0_TEST_3 | 1584.7 | 1745.06 | 90.81 |
| TP_CPU1_PE_HP_SCL | 23.1 | 23.1 | 100 |
| TP_CPU1_PE_HP_SDA | 23.1 | 23.1 | 100 |
| TP_CPU1_RSVD_1 | 79.63 | 108.98 | 73.069999999999993 |
| TP_CPU1_RSVD_2 | 152.24 | 179.54 | 84.79 |
| TP_CPU1_RSVD_3 | 23.1 | 23.1 | 100 |
| TP_CPU1_RSVD_4 | 23.1 | 23.1 | 100 |
| TP_CPU1_RSVD_5 | 23.1 | 23.1 | 100 |
| TP_CPU1_RSVD_6 | 106.37 | 92.5 | 114.99 |
| TP_CPU1_RSVD_7 | 23.1 | 23.1 | 100 |
| TP_CPU1_RSVD_8 | 23.1 | 23.1 | 100 |
| TP_CPU1_RSVD_11 | 23.1 | 23.1 | 100 |
| TP_CPU1_RSVD_12 | 23.1 | 23.1 | 100 |
| TP_CPU1_RSVD_13 | 23.1 | 23.1 | 100 |
| TP_CPU1_RSVD_14 | 23.1 | 23.1 | 100 |
| TP_CPU1_RSVD_15 | 23.1 | 23.1 | 100 |
| TP_CPU1_RSVD_16 | 23.1 | 23.1 | 100 |
| TP_CPU1_RSVD_17 | 23.1 | 23.1 | 100 |
| TP_CPU1_RSVD_18 | 23.1 | 23.1 | 100 |
| TP_CPU1_RSVD_19 | 23.1 | 23.1 | 100 |
| TP_CPU1_RSVD_20 | 23.1 | 23.1 | 100 |
| TP_CPU1_RSVD_21 | 23.1 | 23.1 | 100 |
| TP_CPU1_RSVD_22 | 23.1 | 23.1 | 100 |
| TP_CPU1_RSVD_24 | 23.1 | 23.1 | 100 |
| TP_CPU1_RSVD_25 | 23.1 | 23.1 | 100 |
| TP_CPU1_RSVD_26 | 23.1 | 23.1 | 100 |
| TP_CPU1_RSVD_27 | 23.26 | 23.28 | 99.92 |
| TP_CPU1_RSVD_28 | 23.16 | 23.18 | 99.92 |
| TP_CPU1_RSVD_29 | 23.1 | 23.1 | 100 |
| TP_CPU1_RSVD_30 | 23.1 | 23.1 | 100 |
| TP_CPU1_RSVD_33 | 23.1 | 23.1 | 100 |
| TP_CPU1_RSVD_34 | 23.1 | 23.1 | 100 |
| TP_CPU1_RSVD_35 | 23.1 | 23.1 | 100 |
| TP_CPU1_RSVD_36 | 74.680000000000007 | 93.87 | 79.56 |
| TP_CPU1_RSVD_37 | 39.64 | 52.33 | 75.75 |
| TP_CPU1_RSVD_38 | 153.83000000000001 | 179.17 | 85.86 |
| TP_CPU1_RSVD_39 | 69.91 | 74.849999999999994 | 93.39 |
| TP_CPU1_RSVD_40 | 87.56 | 102.27 | 85.62 |
| TP_CPU1_RSVD_44 | 23.1 | 23.1 | 100 |
| TP_CPU1_RSVD_45 | 23.1 | 23.1 | 100 |
| TP_CPU1_RSVD_46 | 23.1 | 23.1 | 100 |
| TP_CPU1_RSVD_48 | 23.1 | 23.1 | 100 |
| TP_CPU1_RSVD_49 | 23.1 | 23.1 | 100 |
| TP_CPU1_RSVD_50 | 23.1 | 23.1 | 100 |
| TP_CPU1_RSVD_51 | 23.1 | 23.1 | 100 |
| TP_CPU1_RSVD_52 | 23.1 | 23.1 | 100 |
| TP_CPU1_RSVD_53 | 23.1 | 23.1 | 100 |
| TP_CPU1_RSVD_54 | 23.1 | 23.1 | 100 |
| TP_CPU1_RSVD_55 | 23.1 | 23.1 | 100 |
| TP_CPU1_RSVD_56 | 23.1 | 23.1 | 100 |
| TP_CPU1_RSVD_57 | 23.1 | 23.1 | 100 |
| TP_CPU1_RSVD_58 | 23.1 | 23.1 | 100 |
| TP_CPU1_RSVD_59 | 23.1 | 23.1 | 100 |
| TP_CPU1_RSVD_60 | 23.1 | 23.1 | 100 |
| TP_CPU1_RSVD_61 | 23.1 | 23.1 | 100 |
| TP_CPU1_RSVD_62 | 23.1 | 23.1 | 100 |
| TP_CPU1_RSVD_63 | 23.1 | 23.1 | 100 |
| TP_CPU1_RSVD_64 | 23.1 | 23.1 | 100 |
| TP_CPU1_RSVD_65 | 23.1 | 23.1 | 100 |
| TP_CPU1_RSVD_66 | 23.1 | 23.1 | 100 |
| TP_CPU1_RSVD_67 | 23.1 | 23.1 | 100 |
| TP_CPU1_RSVD_68 | 28.09 | 30.61 | 91.77 |
| TP_CPU1_RSVD_70 | 23.01 | 23.03 | 99.9 |
| TP_CPU1_RSVD_71 | 39.67 | 52.97 | 74.89 |
| TP_CPU1_RSVD_72 | 71.7 | 76.069999999999993 | 94.26 |
| TP_CPU1_RSVD_73 | 27.4 | 28.61 | 95.78 |
| TP_CPU1_RSVD_76 | 35.130000000000003 | 40.24 | 87.29 |
| TP_CPU1_RSVD_77 | 24.45 | 31.06 | 78.709999999999994 |
| TP_CPU1_RSVD_78 | 36.42 | 40.68 | 89.53 |
| TP_CPU1_RSVD_79 | 71.760000000000005 | 92.1 | 77.92 |
| TP_CPU1_RSVD_80 | 23.1 | 23.1 | 100 |
| TP_CPU1_RSVD_81 | 23.1 | 23.1 | 100 |
| TP_CPU1_RSVD_82 | 23.02 | 23.04 | 99.92 |
| TP_CPU1_RSVD_83 | 22.79 | 22.83 | 99.82 |
| TP_CPU1_TEST_0 | 1293.55 | 1776.79 | 72.8 |
| TP_CPU1_TEST_1 | 1394.18 | 1888.13 | 73.84 |
| TP_CPU1_TEST_2 | 1400.37 | 1700.2 | 82.36 |
| TP_CPU1_TEST_3 | 1338.33 | 1670.9 | 80.099999999999994 |
| TP_PCH_HDA_BCLK | 303.31 | 301.27999999999997 | 100.67 |
| TP_PCH_HDA_RST_N | 232.62 | 254.33 | 91.46 |
| TP_PCH_HDA_SDI0 | 231.46 | 227.75 | 101.63 |
| TP_PCH_HDA_SDI1 | 283.52999999999997 | 279.27999999999997 | 101.52 |
| TP_PCH_HDA_SDI2 | 296.56 | 357.85 | 82.87 |
| TP_PCH_HDA_SDI3 | 285.77 | 346.85 | 82.39 |
| TP_PCH_HDA_SYNC | 208.78 | 259.27999999999997 | 80.52 |
| TP_PCH_PMTEST_RST | 136.69 | 155.74 | 87.77 |
| TP_PCH_RSVD_2 | 248.22 | 231.31 | 107.31 |
| TP_PCH_RSVD_3 | 454.99 | 344.31 | 132.13999999999999 |
| TP_PCH_RSVD_4 | 64.42 | 32.4 | 198.83 |
| TP_PCI_PME_N | 234.96 | 219.02 | 107.28 |
| TP_PM_SYNC2 | 161.83000000000001 | 173.88 | 93.07 |
| TP_RST_PLTRST_CPU_1V05_N | 105.27 | 75.540000000000006 | 139.35 |
| TP_SDP0 | 74.89 | 84.88 | 88.23 |
| TP_SDP2 | 152.66999999999999 | 181.56 | 84.09 |
| TP_SDP3 | 74.61 | 84.13 | 88.69 |
| TP_SGPIO_BMC_LD_BUF_LVC3_N | 204.46 | 95.68 | 213.7 |
| TP_SGPIO_SATAX_DATAOUT1 | 330.26 | 369.78 | 89.31 |
| TP_SLPS5_N | 475.71 | 467.6 | 101.74 |
| TP_SLPSUS_N_BUFF | 244.94 | 258.48 | 94.76 |
| TP_SLP_LAN_N | 213.62 | 222.14 | 96.16 |
| TP_SPI_CS1 | 112.07 | 147.44999999999999 | 76.010000000000005 |
| TP_SPI_CS2 | 66.66 | 15.36 | 433.97 |
| TP_VCCDUSBSUS_1P05 | 87.19 | 93.19 | 93.56 |
| TP_VCCUSB3SUS_1P05 | 78.760000000000005 | 56.52 | 139.35 |
| TP_XDP_BUF_BO0 | 117.28 | 132.47 | 88.53 |
| TP_XDP_BUF_BO2 | 128.78 | 162.4 | 79.3 |
| TP_XDP_CPU_OBSDATA_C_MBP2 | 110.91 | 127.53 | 86.96 |
| TP_XDP_CPU_OBSDATA_C_MBP3 | 169.79 | 157.83000000000001 | 107.58 |
| TP_XDP_CPU_OBSDATA_C_MBP4 | 109.23 | 123.48 | 88.46 |
| TP_XDP_CPU_OBSDATA_C_MBP5 | 167.84 | 153.78 | 109.15 |
| TP_XDP_CPU_OBSDATA_D_MBP2 | 106.01 | 115.28 | 91.96 |
| TP_XDP_CPU_OBSDATA_D_MBP3 | 164.62 | 153.32 | 107.37 |
| TP_XDP_CPU_OBSDATA_D_MBP4 | 104.31 | 111.18 | 93.82 |
| TP_XDP_CPU_OBSDATA_D_MBP5 | 168.52 | 157.37 | 107.09 |
| TP_XDP_CPU_OBSFN_C0 | 112.58 | 131.58000000000001 | 85.56 |
| TP_XDP_CPU_OBSFN_C1 | 180.74 | 161.88 | 111.65 |
| TP_XDP_CPU_OBSFN_D0 | 107.68 | 119.33 | 90.24 |
| TP_XDP_CPU_OBSFN_D1 | 168.56 | 149.63 | 112.65 |
| TP_XDP_CPU_TCK1 | 232.11 | 265.33 | 87.48 |
| U166_Y | 172.33 | 202.58 | 85.07 |
| U171_OE | 205.58 | 192.19 | 106.96 |
| U173_OE | 166.7 | 207.28 | 80.42 |
| U174_2 | 219.59 | 199.59 | 110.02 |
| U177_1 | 130.62 | 168.4 | 77.56 |
| U177_2 | 17754.32 | 16528.5 | 107.42 |
| U27_HOLD_N | 121.45 | 141 | 86.13 |
| U27_WP_N | 179.59 | 123 | 146.01 |
| U52_2 | 131.81 | 82.32 | 160.12 |
| U52_6 | 389.96 | 171.6 | 227.25 |
| U53_2 | 194.56 | 88.7 | 219.35 |
| U81_EN_N | 573.34 | 293.99 | 195.02 |
| UART_LED_L | 73.31 | 84.9 | 86.35 |
| UART_LED_R | 281.79000000000002 | 352.88 | 79.86 |
| UART_PWR_SEL | 1594.3 | 1413.8 | 112.77 |
| UART_SELECT | 8143.34 | 5362.38 | 151.86000000000001 |
| UART_SELECT_CPLD | 210.25 | 222.03 | 94.69 |
| UART_SELECT_D1_N | 152.99 | 130 | 117.69 |
| UART_SELECT_D2_N | 107 | 107 | 100 |
| UART_SELECT_D3_N | 416.74 | 402.75 | 103.47 |
| UART_SELECT_D3_Q_N | 402.05 | 390.85 | 102.87 |
| UART_SELECT_D3_R_N | 776.46 | 587.75 | 132.11000000000001 |
| UART_SELECT_N | 3997.41 | 4358.1099999999997 | 91.72 |
| UART_SELECT_Q4 | 108.31 | 108.75 | 99.6 |
| UART_SELECT_Q4_N | 341.5 | 272.25 | 125.44 |
| USB2_00_DN | 6033.99 | 5500.24 | 109.7 |
| USB2_00_DP | 6036.31 | 5499.05 | 109.77 |
| USB2_01_DN | 4369.22 | 2157.56 | 202.51 |
| USB2_01_DN_FB | 487.24 | 475.15 | 102.54 |
| USB2_01_DP | 4369.49 | 2197.6799999999998 | 198.82 |
| USB2_01_DP_FB | 485.03 | 350.15 | 138.52000000000001 |
| USB2_02_DN | 7288.89 | 5516.07 | 132.13999999999999 |
| USB2_02_DP | 7290.58 | 5508.07 | 132.36000000000001 |
| USB2_02_INT_CN_DN | 612.16999999999996 | 477.17 | 128.29 |
| USB2_02_INT_CN_DP | 611.99 | 549.16999999999996 | 111.44 |
| USB2_DN | 198.34 | 157.47999999999999 | 125.94 |
| USB2_DP | 198.42 | 166.24 | 119.36 |
| USB2_OC0_INT_N | 4485.13 | 3982.52 | 112.62 |
| USB2_OC1_FP_N | 5749.02 | 4159.16 | 138.22999999999999 |
| USB3_01_RXN | 3014.71 | 1797.38 | 167.73 |
| USB3_01_RXN_FB | 855.91 | 896.93 | 95.43 |
| USB3_01_RXP | 3012.52 | 1866.93 | 161.36000000000001 |
| USB3_01_RXP_FB | 854.61 | 790.93 | 108.05 |
| USB3_01_TXN | 208.68 | 198.08 | 105.35 |
| USB3_01_TXN_C | 3066.46 | 2032.07 | 150.9 |
| USB3_01_TXN_FB | 603.63 | 625.58000000000004 | 96.49 |
| USB3_01_TXP | 209.06 | 202.08 | 103.45 |
| USB3_01_TXP_C | 3064.64 | 2105.66 | 145.54 |
| USB3_01_TXP_FB | 602.41999999999996 | 545.63 | 110.41 |
| USB3_02_RXN | 7653.38 | 6227.79 | 122.89 |
| USB3_02_RXN_FB | 688.69 | 773.8 | 89 |
| USB3_02_RXP | 7652.62 | 6156.79 | 124.3 |
| USB3_02_RXP_FB | 688.54 | 654.05999999999995 | 105.27 |
| USB3_02_TXN | 276.36 | 219.52 | 125.89 |
| USB3_02_TXN_C | 6698.21 | 6458.52 | 103.71 |
| USB3_02_TXN_FB | 423.69 | 444.32 | 95.36 |
| USB3_02_TXP | 280.08 | 223.52 | 125.3 |
| USB3_02_TXP_C | 6695.86 | 6384.52 | 104.88 |
| USB3_02_TXP_FB | 425.16 | 365.22 | 116.41 |
| USBV33A | 22.27 | 748.49 | 2.98 |
| UV_10D5V_N | 22302.38 | 18801.009999999998 | 118.62 |
| UV_FAN_ALERT_N | 207.89 | 198.7 | 104.63 |
| UV_FPH_EN | 7976.14 | 6080.71 | 131.16999999999999 |
| UV_FPH_LEVEL_SEL | 26426.39 | 21152.89 | 124.93 |
| V1PLLAV12 | 305.83999999999997 | 352.18 | 86.84 |
| VBAT_MEAS_EN | 1342.52 | 1328.63 | 101.05 |
| VCCAXCK_DCB_PCH | 201.64 | 180.17 | 111.92 |
| VCCAXCK_VRM_1P5_PCH | 136.76 | 65.510000000000005 | 208.76 |
| VCCA_DMI_PLL_PCH | 207.61 | 211.71 | 98.06 |
| VCCA_SATA3X_PLL_PCH | 438.91 | 441.85 | 99.33 |
| VCCA_SATA3_PLL_PCH | 565.96 | 561.30999999999995 | 100.83 |
| VCCA_USB3_PLL_PCH | 121.51 | 368.31 | 32.99 |
| VCCCLK3_3 | 0 | 487.96 | 0 |
| VDDA_DB1900 | 303.77999999999997 | 289.52999999999997 | 104.92 |
| VDDR_DB1900 | 267.47000000000003 | 160.5 | 166.65 |
| VDD_DB1900 | 446.22 | 1752.1 | 25.47 |
| VOLTAGE_ALERT_N | 27982.11 | 23582.41 | 118.66 |
| VOLTAGE_ALERT_N_PLD | 266.18 | 231.83 | 114.82 |
| VOLTAGE_MODE | 368.97 | 384.72 | 95.91 |
| VOLTAGE_SET | 362.17 | 249.06 | 145.41 |
| VOLTAGE_SET_R | 165.16 | 202.39 | 81.61 |
| VR_FAIL_PVCC_CPU_N | 31724.89 | 27216.560000000001 | 116.56 |
| VSENSE_PVCCIN_CPU0_N | 3528.82 | 3761.6 | 93.81 |
| VSENSE_PVCCIN_CPU0_P | 3545.45 | 3763.25 | 94.21 |
| VSENSE_PVCCIN_CPU1_N | 2550.89 | 2773.69 | 91.97 |
| VSENSE_PVCCIN_CPU1_P | 2531.0700000000002 | 2803.31 | 90.29 |
| WDTRST | 222.52 | 291.66000000000003 | 76.290000000000006 |
| WOL_LVC3_ROW | 1343.71 | 828.69 | 162.15 |
| XDP_CPU0_OBSDATA_A_MBP2_G_N | 4462.72 | 2278.7600000000002 | 195.84 |
| XDP_CPU0_OBSDATA_A_MBP3_G_N | 5024.97 | 2313.7600000000002 | 217.18 |
| XDP_CPU0_OBSDATA_A_MBP4_G_N | 5009.74 | 2289.11 | 218.85 |
| XDP_CPU0_OBSDATA_A_MBP5_G_N | 4616.12 | 2214.71 | 208.43 |
| XDP_CPU0_PRDY_G_N | 21291.09 | 8156.45 | 261.02999999999997 |
| XDP_CPU0_PREQ_G_N | 21222.01 | 8384.39 | 253.11 |
| XDP_CPU0_SKTOCC_N | 539.21 | 634 | 85.05 |
| XDP_CPU0_TDI_G | 4408.12 | 3583.47 | 123.01 |
| XDP_CPU0_TDO_G | 4865.45 | 3777.8 | 128.79 |
| XDP_CPU1_OBSDATA_B_MBP2_G_N | 4311.6499999999996 | 2250.3200000000002 | 191.6 |
| XDP_CPU1_OBSDATA_B_MBP3_G_N | 4277.57 | 2245.3200000000002 | 190.51 |
| XDP_CPU1_OBSDATA_B_MBP4_G_N | 4289.51 | 2261.58 | 189.67 |
| XDP_CPU1_OBSDATA_B_MBP5_G_N | 4328.6099999999997 | 2226.5300000000002 | 194.41 |
| XDP_CPU1_PRDY_G_N | 15243.92 | 11058.7 | 137.85 |
| XDP_CPU1_PREQ_G_N | 15552.29 | 11046.2 | 140.79 |
| XDP_CPU1_SKTOCC_N | 901.26 | 865.48 | 104.13 |
| XDP_CPU1_TDI_G | 3271.04 | 3094.8 | 105.69 |
| XDP_CPU1_TDO_G | 2309.7399999999998 | 2657.63 | 86.91 |
| XDP_CPU_EN | 555.13 | 514.79999999999995 | 107.83 |
| XDP_CPU_MBP0_G_N | 6877 | 5064.8100000000004 | 135.78 |
| XDP_CPU_MBP1_G_N | 6791.55 | 5229.22 | 129.88 |
| XDP_CPU_OBSFN_B_MBP6_G_N | 10499.07 | 4869.2299999999996 | 215.62 |
| XDP_CPU_OBSFN_B_MBP7_G_N | 10225.049999999999 | 4928.6899999999996 | 207.46 |
| XDP_CPU_PWRGD | 156.06 | 160.94 | 96.97 |
| XDP_CPU_RST_N | 187.48 | 181.31 | 103.4 |
| XDP_CPU_SYSPWROK | 13404.72 | 9111.7999999999993 | 147.11000000000001 |
| XDP_CPU_TCK_G | 9072.42 | 5258.71 | 172.52 |
| XDP_CPU_TDI | 726.5 | 949.08 | 76.55 |
| XDP_CPU_TDO | 1463.55 | 1687.22 | 86.74 |
| XDP_CPU_TMS_G | 8965.66 | 5149.3100000000004 | 174.11 |
| XDP_CPU_TRST_G_N | 7760.29 | 5591.71 | 138.78 |
| XDP_PCH_TCK0 | 554.80999999999995 | 427.54 | 129.77000000000001 |
| XDP_PCH_TDI | 1352.22 | 1203.51 | 112.36 |
| XDP_PCH_TDO | 480.08 | 554.22 | 86.62 |
| XDP_PCH_TMS | 283.72000000000003 | 351.79 | 80.650000000000006 |
| XDP_PRESENT_N | 7776.95 | 7775.03 | 100.02 |
| XDP_PRESENT_R_N | 298.68 | 273.89999999999998 | 109.05 |
| XDP_PWRGD_RST_N | 14352.49 | 9254.06 | 155.09 |
| XDP_RST_CO_N | 14461.3 | 9489.7800000000007 | 152.38999999999999 |
| XTAL_IN_I210 | 123.92 | 136.06 | 91.08 |
| XTAL_IN_I210_R | 215.32 | 272.33999999999997 | 79.06 |
| XTAL_IN_MNG | 352.78 | 372.29 | 94.76 |
| XTAL_OUT_I210 | 125.86 | 115.91 | 108.58 |
| XTAL_OUT_I210_R | 215.66 | 265.22000000000003 | 81.31 |
| XTAL_OUT_MNG | 351 | 314.61 | 111.57 |
| XTAL_PCH_25M_IN | 880.48 | 846.52 | 104.01 |
| XTAL_PCH_25M_OUT | 888.97 | 818.52 | 108.61 |
| XTAL_PCH_RTC1 | 480.86 | 506.93 | 94.86 |
| XTAL_PCH_RTC2 | 480.51 | 491.93 | 97.68 |
